FILE_TYPE = MACRO_DRAWING;
SET COLOR_WIRE YELLOW;
SET COLOR_PROP MONO;
SET COLOR_DOT WHITE;
SET COLOR_ARC YELLOW;
SET COLOR_BODY GREEN;
SET COLOR_NOTE MONO;
SET PROP_DISPLAY VALUE;
SET PAGE_NUMBER P213;
FORCEADD P3V3_STBY..1
(1875 4725);
FORCEPROP 3 LASTPIN (1875 4675) SIG_NAME P3V3_STBY\g
J 0
(1885 4685);
DISPLAY 0.659574 (1885 4685);
PAINT MONO (1885 4685);
DISPLAY INVISIBLE (1885 4685);
FORCEPROP 1 LAST HDL_POWER P3V3_STBY
J 0
(1575 4600);
DISPLAY 0.872340 (1575 4600);
PAINT ORANGE (1575 4600);
DISPLAY INVISIBLE (1575 4600);
FORCEPROP 1 LAST PATH I1
J 0
(1920 4727);
DISPLAY 0.340426 (1920 4727);
PAINT GREEN (1920 4727);
DISPLAY INVISIBLE (1920 4727);
FORCEPROP 1 LAST BODY_TYPE PLUMBING
J 0
(1830 4682);
DISPLAY 0.340426 (1830 4682);
PAINT GREEN (1830 4682);
DISPLAY INVISIBLE (1830 4682);
FORCEPROP 2 LAST CDS_LIB mstr_symbols
J 0
(1875 4725);
PAINT ORANGE (1875 4725);
DISPLAY INVISIBLE (1875 4725);
FORCEPROP 1 LAST SIZE 1B
J 0
(1920 4747);
DISPLAY 0.340426 (1920 4747);
PAINT GREEN (1920 4747);
DISPLAY INVISIBLE (1920 4747);
FORCEPROP 1 LAST VOLTAGE 3.3V
J 0
(1830 4682);
DISPLAY 0.340426 (1830 4682);
PAINT SKYBLUE (1830 4682);
DISPLAY INVISIBLE (1830 4682);
FORCEADD GND..1
(2425 1275);
FORCEPROP 3 LASTPIN (2425 1325) SIG_NAME GND\g
J 0
(2435 1335);
DISPLAY 0.659574 (2435 1335);
PAINT MONO (2435 1335);
DISPLAY INVISIBLE (2435 1335);
FORCEPROP 2 LAST ROOM PVCCIO_CPU1
J 0
(1850 1350);
DISPLAY 1.361702 (1850 1350);
PAINT ORANGE (1850 1350);
DISPLAY INVISIBLE (1850 1350);
FORCEPROP 1 LAST BODY_TYPE PLUMBING
J 0
(2380 1232);
DISPLAY 0.340426 (2380 1232);
PAINT GREEN (2380 1232);
DISPLAY INVISIBLE (2380 1232);
FORCEPROP 1 LAST SIZE 1B
J 0
(2500 1225);
DISPLAY 1.170213 (2500 1225);
PAINT AQUA (2500 1225);
DISPLAY INVISIBLE (2500 1225);
FORCEPROP 2 LAST CDS_LIB mstr_symbols
J 0
(2425 1275);
PAINT ORANGE (2425 1275);
DISPLAY INVISIBLE (2425 1275);
FORCEPROP 1 LAST VOLTAGE 0
J 0
(2425 1275);
PAINT SKYBLUE (2425 1275);
DISPLAY INVISIBLE (2425 1275);
FORCEPROP 1 LAST PATH I10
J 0
(2500 1275);
DISPLAY 0.872340 (2500 1275);
PAINT AQUA (2500 1275);
DISPLAY INVISIBLE (2500 1275);
FORCEPROP 1 LAST HDL_POWER GND
J 0
(2425 1425);
DISPLAY 1.170213 (2425 1425);
PAINT GREEN (2425 1425);
DISPLAY INVISIBLE (2425 1425);
FORCEADD CAP_A..1
(2025 1575);
FORCEPROP 1 LASTPIN (2025 1475) $PN 2
J 0
(2035 1455);
DISPLAY 0.617021 (2035 1455);
PAINT ORANGE (2035 1455);
FORCEPROP 1 LASTPIN (2025 1675) $PN 1
J 0
(2035 1655);
DISPLAY 0.617021 (2035 1655);
PAINT ORANGE (2035 1655);
FORCEPROP 1 LAST PACK_TYPE 0402V
J 0
(2075 1375);
DISPLAY 0.617021 (2075 1375);
PAINT SKYBLUE (2075 1375);
FORCEPROP 1 LAST MATERIAL X7R
J 0
(2075 1475);
DISPLAY 0.617021 (2075 1475);
PAINT SKYBLUE (2075 1475);
FORCEPROP 1 LAST PART_NUMBER A36096-030
J 0
(2075 1425);
DISPLAY 0.617021 (2075 1425);
PAINT BLUE (2075 1425);
FORCEPROP 1 LAST TOLERANCE 10%
J 0
(2075 1525);
DISPLAY 0.617021 (2075 1525);
PAINT SKYBLUE (2075 1525);
FORCEPROP 1 LAST VOLTAGE 16V
J 0
(2075 1575);
DISPLAY 0.617021 (2075 1575);
PAINT SKYBLUE (2075 1575);
FORCEPROP 1 LAST VALUE 0.1UF
J 0
(2075 1625);
DISPLAY 0.617021 (2075 1625);
PAINT SKYBLUE (2075 1625);
FORCEPROP 1 LAST LOCATION C4D32
J 0
(2075 1675);
DISPLAY 0.617021 (2075 1675);
PAINT AQUA (2075 1675);
FORCEPROP 2 LAST CDS_LIB dev_discrete
J 0
(2025 1575);
PAINT ORANGE (2025 1575);
DISPLAY INVISIBLE (2025 1575);
FORCEPROP 2 LAST SEC 1
J 0
(2075 1800);
DISPLAY 0.680851 (2075 1800);
PAINT MONO (2075 1800);
DISPLAY INVISIBLE (2075 1800);
FORCEPROP 2 LAST SEC_TYPE 0402V
J 0
(2075 1800);
DISPLAY 1.021277 (2075 1800);
PAINT ORANGE (2075 1800);
DISPLAY INVISIBLE (2075 1800);
FORCEPROP 2 LAST CDS_SEC 1
J 0
(2075 1725);
PAINT ORANGE (2075 1725);
DISPLAY INVISIBLE (2075 1725);
FORCEPROP 2 LAST CDS_LOCATION C4D32
J 0
(2075 1675);
DISPLAY 0.617021 (2075 1675);
PAINT AQUA (2075 1675);
DISPLAY INVISIBLE (2075 1675);
FORCEPROP 2 LAST ROOM PVCCIO_CPU1
J 0
(2075 1725);
DISPLAY 1.361702 (2075 1725);
PAINT ORANGE (2075 1725);
DISPLAY INVISIBLE (2075 1725);
FORCEPROP 1 LAST PATH I11
J 0
(2075 1725);
DISPLAY 0.978723 (2075 1725);
PAINT WHITE (2075 1725);
DISPLAY INVISIBLE (2075 1725);
FORCEADD GND..1
(2025 1375);
FORCEPROP 3 LASTPIN (2025 1425) SIG_NAME GND\g
J 0
(2035 1435);
DISPLAY 0.659574 (2035 1435);
PAINT MONO (2035 1435);
DISPLAY INVISIBLE (2035 1435);
FORCEPROP 2 LAST ROOM PVCCIO_CPU1
J 0
(1450 1450);
DISPLAY 1.361702 (1450 1450);
PAINT ORANGE (1450 1450);
DISPLAY INVISIBLE (1450 1450);
FORCEPROP 2 LAST CDS_LIB mstr_symbols
J 0
(2025 1375);
PAINT ORANGE (2025 1375);
DISPLAY INVISIBLE (2025 1375);
FORCEPROP 1 LAST VOLTAGE 0
J 0
(2025 1375);
PAINT SKYBLUE (2025 1375);
DISPLAY INVISIBLE (2025 1375);
FORCEPROP 1 LAST BODY_TYPE PLUMBING
J 0
(1980 1332);
DISPLAY 0.340426 (1980 1332);
PAINT GREEN (1980 1332);
DISPLAY INVISIBLE (1980 1332);
FORCEPROP 1 LAST HDL_POWER GND
J 0
(2025 1525);
DISPLAY 1.170213 (2025 1525);
PAINT GREEN (2025 1525);
DISPLAY INVISIBLE (2025 1525);
FORCEPROP 1 LAST SIZE 1B
J 0
(2100 1325);
DISPLAY 1.170213 (2100 1325);
PAINT AQUA (2100 1325);
DISPLAY INVISIBLE (2100 1325);
FORCEPROP 1 LAST PATH I12
J 0
(2100 1375);
DISPLAY 0.872340 (2100 1375);
PAINT AQUA (2100 1375);
DISPLAY INVISIBLE (2100 1375);
FORCEADD RES..1
(1950 3575);
FORCEPROP 1 LAST WATTAGE 1/16W
J 2
(1925 3425);
DISPLAY 0.617021 (1925 3425);
PAINT SKYBLUE (1925 3425);
FORCEPROP 1 LAST VALUE 22.1
J 2
(1925 3475);
DISPLAY 0.617021 (1925 3475);
PAINT SKYBLUE (1925 3475);
FORCEPROP 1 LASTPIN (1850 3575) $PN 1
J 0
(1862 3587);
DISPLAY 0.617021 (1862 3587);
PAINT ORANGE (1862 3587);
FORCEPROP 1 LASTPIN (2050 3575) $PN 2
J 0
(2012 3587);
DISPLAY 0.617021 (2012 3587);
PAINT ORANGE (2012 3587);
FORCEPROP 1 LAST LOCATION R4D46
J 0
(1900 3625);
DISPLAY 0.617021 (1900 3625);
PAINT AQUA (1900 3625);
FORCEPROP 1 LAST MATERIAL CHIP
J 0
(1950 3425);
DISPLAY 0.617021 (1950 3425);
PAINT SKYBLUE (1950 3425);
FORCEPROP 1 LAST TOLERANCE 1.0%
J 0
(1950 3475);
DISPLAY 0.617021 (1950 3475);
PAINT SKYBLUE (1950 3475);
FORCEPROP 1 LAST PART_NUMBER G21796-250
J 0
(1900 3675);
DISPLAY 0.617021 (1900 3675);
PAINT BLUE (1900 3675);
FORCEPROP 1 LAST PACK_TYPE 0402
J 0
(2200 3425);
DISPLAY 0.617021 (2200 3425);
PAINT SKYBLUE (2200 3425);
FORCEPROP 2 LAST CDS_LIB mstr_discrete
J 0
(1950 3575);
PAINT MONO (1950 3575);
DISPLAY INVISIBLE (1950 3575);
FORCEPROP 2 LAST ROOM PVCCIO_CPU1
J 0
(1900 3675);
DISPLAY 1.361702 (1900 3675);
PAINT ORANGE (1900 3675);
DISPLAY INVISIBLE (1900 3675);
FORCEPROP 1 LAST PATH I13
J 0
(1900 3725);
DISPLAY 0.978723 (1900 3725);
PAINT WHITE (1900 3725);
DISPLAY INVISIBLE (1900 3725);
FORCEPROP 2 LAST CDS_LOCATION R4D46
J 0
(1900 3625);
DISPLAY 0.617021 (1900 3625);
PAINT AQUA (1900 3625);
DISPLAY INVISIBLE (1900 3625);
FORCEPROP 2 LAST SEC 1
J 0
(1900 3775);
DISPLAY 0.680851 (1900 3775);
PAINT MONO (1900 3775);
DISPLAY INVISIBLE (1900 3775);
FORCEPROP 2 LAST SEC_TYPE 0402
J 0
(1900 3775);
DISPLAY 1.021277 (1900 3775);
PAINT ORANGE (1900 3775);
DISPLAY INVISIBLE (1900 3775);
FORCEADD RES..2
(1600 4075);
FORCEPROP 1 LASTPIN (1600 3975) $PN 2
J 0
(1605 3985);
DISPLAY 0.617021 (1605 3985);
PAINT ORANGE (1605 3985);
FORCEPROP 1 LAST WATTAGE 1/16W
J 0
(1640 4050);
DISPLAY 0.617021 (1640 4050);
PAINT SKYBLUE (1640 4050);
FORCEPROP 1 LAST PACK_TYPE 0402
J 0
(1640 3900);
DISPLAY 0.617021 (1640 3900);
PAINT SKYBLUE (1640 3900);
FORCEPROP 1 LAST MATERIAL EMPTY
J 0
(1640 4000);
DISPLAY 0.617021 (1640 4000);
PAINT RED (1640 4000);
FORCEPROP 1 LAST PART_NUMBER G21796-311
J 0
(1640 3950);
DISPLAY 0.617021 (1640 3950);
PAINT BLUE (1640 3950);
FORCEPROP 1 LASTPIN (1600 4175) $PN 1
J 0
(1605 4137);
DISPLAY 0.617021 (1605 4137);
PAINT ORANGE (1605 4137);
FORCEPROP 1 LAST TOLERANCE 1.0%
J 0
(1645 4100);
DISPLAY 0.617021 (1645 4100);
PAINT SKYBLUE (1645 4100);
FORCEPROP 1 LAST VALUE 2.26K
J 0
(1645 4150);
DISPLAY 0.617021 (1645 4150);
PAINT SKYBLUE (1645 4150);
FORCEPROP 1 LAST LOCATION R6P49
J 0
(1645 4200);
DISPLAY 0.617021 (1645 4200);
PAINT AQUA (1645 4200);
FORCEPROP 2 LAST ROOM PVCCIO_CPU1
J 0
(1650 4050);
DISPLAY 1.361702 (1650 4050);
PAINT ORANGE (1650 4050);
DISPLAY INVISIBLE (1650 4050);
FORCEPROP 2 LAST CDS_LIB mstr_discrete
J 0
(1600 4075);
PAINT ORANGE (1600 4075);
DISPLAY INVISIBLE (1600 4075);
FORCEPROP 1 LAST PATH I14
J 0
(1650 4250);
DISPLAY 0.978723 (1650 4250);
PAINT WHITE (1650 4250);
DISPLAY INVISIBLE (1650 4250);
FORCEPROP 2 LAST SEC 1
J 0
(1650 4325);
DISPLAY 0.680851 (1650 4325);
PAINT MONO (1650 4325);
DISPLAY INVISIBLE (1650 4325);
FORCEPROP 2 LAST SEC_TYPE 0402
J 0
(1650 4325);
DISPLAY 1.021277 (1650 4325);
PAINT ORANGE (1650 4325);
DISPLAY INVISIBLE (1650 4325);
FORCEADD RES..2
(950 4050);
FORCEPROP 1 LAST WATTAGE 1/16W
J 0
(990 4025);
DISPLAY 0.617021 (990 4025);
PAINT SKYBLUE (990 4025);
FORCEPROP 1 LAST MATERIAL CHIP
J 0
(990 3975);
DISPLAY 0.617021 (990 3975);
PAINT SKYBLUE (990 3975);
FORCEPROP 1 LAST PACK_TYPE 0402
J 0
(990 3875);
DISPLAY 0.617021 (990 3875);
PAINT SKYBLUE (990 3875);
FORCEPROP 1 LAST PART_NUMBER G21796-026
J 0
(990 3925);
DISPLAY 0.617021 (990 3925);
PAINT BLUE (990 3925);
FORCEPROP 1 LAST TOLERANCE 1%
J 0
(995 4075);
DISPLAY 0.617021 (995 4075);
PAINT SKYBLUE (995 4075);
FORCEPROP 1 LAST VALUE 1.00K
J 0
(995 4125);
DISPLAY 0.617021 (995 4125);
PAINT SKYBLUE (995 4125);
FORCEPROP 1 LAST LOCATION R4D42
J 0
(995 4175);
DISPLAY 0.617021 (995 4175);
PAINT AQUA (995 4175);
FORCEPROP 1 LASTPIN (950 3950) $PN 2
J 0
(955 3960);
DISPLAY 0.787234 (955 3960);
PAINT ORANGE (955 3960);
DISPLAY INVISIBLE (955 3960);
FORCEPROP 2 LAST CDS_LIB mstr_discrete
J 0
(950 4050);
PAINT ORANGE (950 4050);
DISPLAY INVISIBLE (950 4050);
FORCEPROP 1 LASTPIN (950 4150) $PN 1
J 0
(955 4112);
DISPLAY 0.787234 (955 4112);
PAINT ORANGE (955 4112);
DISPLAY INVISIBLE (955 4112);
FORCEPROP 2 LAST ROOM PVCCIO_CPU1
J 0
(1000 4225);
DISPLAY 1.361702 (1000 4225);
PAINT ORANGE (1000 4225);
DISPLAY INVISIBLE (1000 4225);
FORCEPROP 1 LAST PATH I15
J 0
(1000 4225);
DISPLAY 0.978723 (1000 4225);
PAINT WHITE (1000 4225);
DISPLAY INVISIBLE (1000 4225);
FORCEPROP 2 LAST CDS_LOCATION R4D42
J 0
(995 4175);
DISPLAY 0.617021 (995 4175);
PAINT AQUA (995 4175);
DISPLAY INVISIBLE (995 4175);
FORCEPROP 2 LAST $SEC 1
J 0
(1000 4275);
PAINT MONO (1000 4275);
DISPLAY INVISIBLE (1000 4275);
FORCEPROP 2 LAST CDS_SEC 1
J 0
(1000 4275);
PAINT MONO (1000 4275);
DISPLAY INVISIBLE (1000 4275);
FORCEADD RES..1
(1375 3125);
FORCEPROP 1 LAST PART_NUMBER G21497-005
J 0
(1225 3025);
DISPLAY 0.617021 (1225 3025);
PAINT BLUE (1225 3025);
FORCEPROP 1 LAST WATTAGE 1/16W
J 2
(1275 3075);
DISPLAY 0.617021 (1275 3075);
PAINT SKYBLUE (1275 3075);
FORCEPROP 1 LAST VALUE 0.0
J 2
(1350 3075);
DISPLAY 0.617021 (1350 3075);
PAINT SKYBLUE (1350 3075);
FORCEPROP 1 LASTPIN (1275 3125) $PN 1
J 0
(1287 3137);
DISPLAY 0.617021 (1287 3137);
PAINT ORANGE (1287 3137);
FORCEPROP 1 LAST TOLERANCE 5%
J 0
(1375 3075);
DISPLAY 0.617021 (1375 3075);
PAINT SKYBLUE (1375 3075);
FORCEPROP 1 LAST LOCATION R4D56
J 0
(1325 3175);
DISPLAY 0.617021 (1325 3175);
PAINT AQUA (1325 3175);
FORCEPROP 1 LASTPIN (1475 3125) $PN 2
J 0
(1437 3137);
DISPLAY 0.617021 (1437 3137);
PAINT ORANGE (1437 3137);
FORCEPROP 1 LAST PACK_TYPE 0402
J 0
(1475 3075);
DISPLAY 0.617021 (1475 3075);
PAINT SKYBLUE (1475 3075);
FORCEPROP 1 LAST MATERIAL CHIP
J 0
(1600 3075);
DISPLAY 0.617021 (1600 3075);
PAINT SKYBLUE (1600 3075);
FORCEPROP 2 LAST ROOM PVCCIO_CPU1
J 0
(1325 3225);
DISPLAY 1.361702 (1325 3225);
PAINT ORANGE (1325 3225);
DISPLAY INVISIBLE (1325 3225);
FORCEPROP 1 LAST PATH I16
J 0
(1325 3275);
DISPLAY 0.978723 (1325 3275);
PAINT WHITE (1325 3275);
DISPLAY INVISIBLE (1325 3275);
FORCEPROP 2 LAST CDS_LOCATION R4D56
J 0
(1325 3175);
DISPLAY 0.617021 (1325 3175);
PAINT AQUA (1325 3175);
DISPLAY INVISIBLE (1325 3175);
FORCEPROP 2 LAST CDS_LIB mstr_discrete
J 0
(1375 3125);
PAINT ORANGE (1375 3125);
DISPLAY INVISIBLE (1375 3125);
FORCEPROP 2 LAST SEC 1
J 0
(1325 3350);
DISPLAY 0.680851 (1325 3350);
PAINT MONO (1325 3350);
DISPLAY INVISIBLE (1325 3350);
FORCEPROP 2 LAST SEC_TYPE 0402
J 0
(1325 3350);
DISPLAY 1.021277 (1325 3350);
PAINT ORANGE (1325 3350);
DISPLAY INVISIBLE (1325 3350);
FORCEADD CAP_A..1
(150 4150);
FORCEPROP 1 LAST PACK_TYPE 0402V
J 0
(200 3950);
DISPLAY 0.617021 (200 3950);
PAINT SKYBLUE (200 3950);
FORCEPROP 1 LAST PART_NUMBER D97712-004
J 0
(200 4000);
DISPLAY 0.617021 (200 4000);
PAINT BLUE (200 4000);
FORCEPROP 1 LAST MATERIAL X6S
J 0
(200 4050);
DISPLAY 0.617021 (200 4050);
PAINT SKYBLUE (200 4050);
FORCEPROP 1 LAST VOLTAGE 6.3V
J 0
(200 4150);
DISPLAY 0.617021 (200 4150);
PAINT SKYBLUE (200 4150);
FORCEPROP 1 LAST TOLERANCE 10%
J 0
(200 4100);
DISPLAY 0.617021 (200 4100);
PAINT SKYBLUE (200 4100);
FORCEPROP 1 LAST VALUE 1.0UF
J 0
(200 4200);
DISPLAY 0.617021 (200 4200);
PAINT SKYBLUE (200 4200);
FORCEPROP 1 LAST LOCATION C4D36
J 0
(200 4250);
DISPLAY 0.617021 (200 4250);
PAINT AQUA (200 4250);
FORCEPROP 1 LASTPIN (150 4050) $PN 2
J 0
(160 4030);
DISPLAY 0.787234 (160 4030);
PAINT ORANGE (160 4030);
DISPLAY INVISIBLE (160 4030);
FORCEPROP 2 LAST CDS_LIB dev_discrete
J 0
(150 4150);
PAINT ORANGE (150 4150);
DISPLAY INVISIBLE (150 4150);
FORCEPROP 1 LAST PATH I17
J 0
(200 4300);
DISPLAY 0.978723 (200 4300);
PAINT WHITE (200 4300);
DISPLAY INVISIBLE (200 4300);
FORCEPROP 1 LASTPIN (150 4250) $PN 1
J 0
(160 4230);
DISPLAY 0.787234 (160 4230);
PAINT ORANGE (160 4230);
DISPLAY INVISIBLE (160 4230);
FORCEPROP 2 LAST CDS_LOCATION C4D36
J 0
(200 4250);
DISPLAY 0.617021 (200 4250);
PAINT AQUA (200 4250);
DISPLAY INVISIBLE (200 4250);
FORCEPROP 2 LAST $SEC 1
J 0
(200 4350);
DISPLAY 0.680851 (200 4350);
PAINT MONO (200 4350);
DISPLAY INVISIBLE (200 4350);
FORCEPROP 2 LAST CDS_SEC 1
J 0
(200 4350);
PAINT MONO (200 4350);
DISPLAY INVISIBLE (200 4350);
FORCEPROP 2 LAST ROOM PVCCIO_CPU1
J 0
(200 4300);
DISPLAY 1.361702 (200 4300);
PAINT ORANGE (200 4300);
DISPLAY INVISIBLE (200 4300);
FORCEADD GND..1
(150 3950);
FORCEPROP 3 LASTPIN (150 4000) SIG_NAME GND\g
J 0
(160 4010);
DISPLAY 0.659574 (160 4010);
PAINT MONO (160 4010);
DISPLAY INVISIBLE (160 4010);
FORCEPROP 2 LAST ROOM PVCCIO_CPU1
J 0
(-425 4025);
DISPLAY 1.361702 (-425 4025);
PAINT ORANGE (-425 4025);
DISPLAY INVISIBLE (-425 4025);
FORCEPROP 1 LAST BODY_TYPE PLUMBING
J 0
(105 3907);
DISPLAY 0.340426 (105 3907);
PAINT GREEN (105 3907);
DISPLAY INVISIBLE (105 3907);
FORCEPROP 1 LAST PATH I18
J 0
(225 3950);
DISPLAY 0.872340 (225 3950);
PAINT AQUA (225 3950);
DISPLAY INVISIBLE (225 3950);
FORCEPROP 1 LAST SIZE 1B
J 0
(225 3900);
DISPLAY 1.170213 (225 3900);
PAINT AQUA (225 3900);
DISPLAY INVISIBLE (225 3900);
FORCEPROP 2 LAST CDS_LIB mstr_symbols
J 0
(150 3950);
PAINT ORANGE (150 3950);
DISPLAY INVISIBLE (150 3950);
FORCEPROP 1 LAST VOLTAGE 0
J 0
(150 3950);
PAINT SKYBLUE (150 3950);
DISPLAY INVISIBLE (150 3950);
FORCEPROP 1 LAST HDL_POWER GND
J 0
(150 4100);
DISPLAY 1.170213 (150 4100);
PAINT GREEN (150 4100);
DISPLAY INVISIBLE (150 4100);
FORCEADD OFFPAGE..2
(2725 3575);
FORCEPROP 2 LAST $XR0 191 
J 0
(2914 3575);
DISPLAY 0.638298 (2914 3575);
PAINT MONO (2914 3575);
FORCEPROP 2 LAST ROOM PVCCIO_CPU1
J 0
(2300 3650);
DISPLAY 1.361702 (2300 3650);
PAINT ORANGE (2300 3650);
DISPLAY INVISIBLE (2300 3650);
FORCEPROP 1 LAST COMMENT_BODY TRUE
J 0
(2680 3480);
DISPLAY 1.170213 (2680 3480);
PAINT GREEN (2680 3480);
DISPLAY INVISIBLE (2680 3480);
FORCEPROP 1 LAST OFFPAGE TRUE
J 0
(3050 3450);
DISPLAY 1.170213 (3050 3450);
PAINT GREEN (3050 3450);
DISPLAY INVISIBLE (3050 3450);
FORCEPROP 2 LAST CDS_LIB mstr_standard
J 0
(2725 3575);
PAINT ORANGE (2725 3575);
DISPLAY INVISIBLE (2725 3575);
FORCEPROP 2 LAST PATH I2
J 0
(2900 3650);
DISPLAY 1.021277 (2900 3650);
PAINT ORANGE (2900 3650);
DISPLAY INVISIBLE (2900 3650);
FORCEADD GND..1
(1000 1875);
FORCEPROP 3 LASTPIN (1000 1925) SIG_NAME GND\g
J 0
(1010 1935);
DISPLAY 0.659574 (1010 1935);
PAINT MONO (1010 1935);
DISPLAY INVISIBLE (1010 1935);
FORCEPROP 2 LAST ROOM PVCCIO_CPU1
J 0
(425 1950);
DISPLAY 1.361702 (425 1950);
PAINT ORANGE (425 1950);
DISPLAY INVISIBLE (425 1950);
FORCEPROP 1 LAST BODY_TYPE PLUMBING
J 0
(955 1832);
DISPLAY 0.340426 (955 1832);
PAINT GREEN (955 1832);
DISPLAY INVISIBLE (955 1832);
FORCEPROP 2 LAST CDS_LIB mstr_symbols
J 0
(1000 1875);
PAINT ORANGE (1000 1875);
DISPLAY INVISIBLE (1000 1875);
FORCEPROP 1 LAST VOLTAGE 0
J 0
(1000 1875);
PAINT SKYBLUE (1000 1875);
DISPLAY INVISIBLE (1000 1875);
FORCEPROP 1 LAST PATH I21
J 0
(1075 1875);
DISPLAY 0.872340 (1075 1875);
PAINT AQUA (1075 1875);
DISPLAY INVISIBLE (1075 1875);
FORCEPROP 1 LAST SIZE 1B
J 0
(1075 1825);
DISPLAY 1.170213 (1075 1825);
PAINT AQUA (1075 1825);
DISPLAY INVISIBLE (1075 1825);
FORCEPROP 1 LAST HDL_POWER GND
J 0
(1000 2025);
DISPLAY 1.170213 (1000 2025);
PAINT GREEN (1000 2025);
DISPLAY INVISIBLE (1000 2025);
FORCEADD P3V3_STBY..1
(-550 4825);
FORCEPROP 3 LASTPIN (-550 4775) SIG_NAME P3V3_STBY\g
J 0
(-540 4785);
DISPLAY 0.659574 (-540 4785);
PAINT MONO (-540 4785);
DISPLAY INVISIBLE (-540 4785);
FORCEPROP 1 LAST HDL_POWER P3V3_STBY
J 0
(-850 4700);
DISPLAY 0.872340 (-850 4700);
PAINT ORANGE (-850 4700);
DISPLAY INVISIBLE (-850 4700);
FORCEPROP 1 LAST BODY_TYPE PLUMBING
J 0
(-595 4782);
DISPLAY 0.340426 (-595 4782);
PAINT GREEN (-595 4782);
DISPLAY INVISIBLE (-595 4782);
FORCEPROP 1 LAST VOLTAGE 3.3V
J 0
(-595 4782);
DISPLAY 0.340426 (-595 4782);
PAINT SKYBLUE (-595 4782);
DISPLAY INVISIBLE (-595 4782);
FORCEPROP 2 LAST CDS_LIB mstr_symbols
J 0
(-550 4825);
PAINT ORANGE (-550 4825);
DISPLAY INVISIBLE (-550 4825);
FORCEPROP 1 LAST PATH I24
J 0
(-505 4827);
DISPLAY 0.340426 (-505 4827);
PAINT GREEN (-505 4827);
DISPLAY INVISIBLE (-505 4827);
FORCEPROP 1 LAST SIZE 1B
J 0
(-505 4847);
DISPLAY 0.340426 (-505 4847);
PAINT GREEN (-505 4847);
DISPLAY INVISIBLE (-505 4847);
FORCEADD RES..2
(-550 4500);
FORCEPROP 1 LAST WATTAGE 1/16W
J 0
(-510 4475);
DISPLAY 0.617021 (-510 4475);
PAINT SKYBLUE (-510 4475);
FORCEPROP 1 LAST MATERIAL CHIP
J 0
(-510 4425);
DISPLAY 0.617021 (-510 4425);
PAINT SKYBLUE (-510 4425);
FORCEPROP 1 LAST PACK_TYPE 0402
J 0
(-510 4325);
DISPLAY 0.617021 (-510 4325);
PAINT SKYBLUE (-510 4325);
FORCEPROP 1 LAST TOLERANCE 5%
J 0
(-505 4525);
DISPLAY 0.617021 (-505 4525);
PAINT SKYBLUE (-505 4525);
FORCEPROP 1 LAST VALUE 0.0
J 0
(-505 4575);
DISPLAY 0.617021 (-505 4575);
PAINT SKYBLUE (-505 4575);
FORCEPROP 1 LAST PART_NUMBER G21497-005
J 0
(-510 4375);
DISPLAY 0.617021 (-510 4375);
PAINT BLUE (-510 4375);
FORCEPROP 1 LAST LOCATION R4D47
J 0
(-505 4625);
DISPLAY 0.617021 (-505 4625);
PAINT AQUA (-505 4625);
FORCEPROP 1 LASTPIN (-550 4400) $PN 2
J 0
(-545 4410);
DISPLAY 0.787234 (-545 4410);
PAINT ORANGE (-545 4410);
DISPLAY INVISIBLE (-545 4410);
FORCEPROP 2 LAST CDS_LIB mstr_discrete
J 0
(-550 4500);
PAINT ORANGE (-550 4500);
DISPLAY INVISIBLE (-550 4500);
FORCEPROP 1 LASTPIN (-550 4600) $PN 1
J 0
(-545 4562);
DISPLAY 0.787234 (-545 4562);
PAINT ORANGE (-545 4562);
DISPLAY INVISIBLE (-545 4562);
FORCEPROP 2 LAST ROOM PVCCIO_CPU1
J 0
(-500 4675);
DISPLAY 1.361702 (-500 4675);
PAINT ORANGE (-500 4675);
DISPLAY INVISIBLE (-500 4675);
FORCEPROP 1 LAST PATH I25
J 0
(-500 4675);
DISPLAY 0.978723 (-500 4675);
PAINT WHITE (-500 4675);
DISPLAY INVISIBLE (-500 4675);
FORCEPROP 2 LAST CDS_LOCATION R4D47
J 0
(-505 4625);
DISPLAY 0.617021 (-505 4625);
PAINT AQUA (-505 4625);
DISPLAY INVISIBLE (-505 4625);
FORCEPROP 2 LAST $SEC 1
J 0
(-500 4725);
PAINT MONO (-500 4725);
DISPLAY INVISIBLE (-500 4725);
FORCEPROP 2 LAST CDS_SEC 1
J 0
(-500 4725);
PAINT MONO (-500 4725);
DISPLAY INVISIBLE (-500 4725);
FORCEADD PVCCIO_CPU1..1
(-1375 4900);
FORCEPROP 3 LASTPIN (-1375 4850) SIG_NAME PVCCIO_CPU1\g
J 0
(-1365 4860);
DISPLAY 0.659574 (-1365 4860);
PAINT MONO (-1365 4860);
DISPLAY INVISIBLE (-1365 4860);
FORCEPROP 1 LAST VOLTAGE 1.1V
J 0
(-1420 4857);
DISPLAY 0.340426 (-1420 4857);
PAINT SKYBLUE (-1420 4857);
DISPLAY INVISIBLE (-1420 4857);
FORCEPROP 2 LAST CDS_LIB mstr_symbols
J 0
(-1375 4900);
PAINT ORANGE (-1375 4900);
DISPLAY INVISIBLE (-1375 4900);
FORCEPROP 1 LAST BODY_TYPE PLUMBING
J 0
(-1420 4857);
DISPLAY 0.340426 (-1420 4857);
PAINT GREEN (-1420 4857);
DISPLAY INVISIBLE (-1420 4857);
FORCEPROP 1 LAST PATH I26
J 0
(-1325 4925);
DISPLAY 0.872340 (-1325 4925);
PAINT AQUA (-1325 4925);
DISPLAY INVISIBLE (-1325 4925);
FORCEPROP 1 LAST HDL_POWER PVCCIO_CPU1
J 1
(-1375 4950);
DISPLAY 0.872340 (-1375 4950);
PAINT GREEN (-1375 4950);
DISPLAY INVISIBLE (-1375 4950);
FORCEADD RES..2
(-1375 4475);
FORCEPROP 1 LAST WATTAGE 1/16W
J 0
(-1335 4450);
DISPLAY 0.617021 (-1335 4450);
PAINT SKYBLUE (-1335 4450);
FORCEPROP 1 LAST PACK_TYPE 0402
J 0
(-1335 4300);
DISPLAY 0.617021 (-1335 4300);
PAINT SKYBLUE (-1335 4300);
FORCEPROP 1 LAST TOLERANCE 1%
J 0
(-1330 4500);
DISPLAY 0.617021 (-1330 4500);
PAINT SKYBLUE (-1330 4500);
FORCEPROP 1 LAST VALUE 100.0
J 0
(-1330 4550);
DISPLAY 0.617021 (-1330 4550);
PAINT SKYBLUE (-1330 4550);
FORCEPROP 1 LAST PART_NUMBER G21796-017
J 0
(-1335 4350);
DISPLAY 0.617021 (-1335 4350);
PAINT BLUE (-1335 4350);
FORCEPROP 1 LAST MATERIAL EMPTY
J 0
(-1335 4400);
DISPLAY 0.617021 (-1335 4400);
PAINT RED (-1335 4400);
FORCEPROP 1 LAST LOCATION R6P35
J 0
(-1330 4600);
DISPLAY 0.617021 (-1330 4600);
PAINT AQUA (-1330 4600);
FORCEPROP 1 LASTPIN (-1375 4375) $PN 2
J 0
(-1370 4385);
DISPLAY 0.787234 (-1370 4385);
PAINT ORANGE (-1370 4385);
DISPLAY INVISIBLE (-1370 4385);
FORCEPROP 2 LAST CDS_LIB mstr_discrete
J 0
(-1375 4475);
PAINT ORANGE (-1375 4475);
DISPLAY INVISIBLE (-1375 4475);
FORCEPROP 1 LASTPIN (-1375 4575) $PN 1
J 0
(-1370 4537);
DISPLAY 0.787234 (-1370 4537);
PAINT ORANGE (-1370 4537);
DISPLAY INVISIBLE (-1370 4537);
FORCEPROP 2 LAST CDS_LOCATION R6P35
J 0
(-1330 4600);
DISPLAY 0.617021 (-1330 4600);
PAINT AQUA (-1330 4600);
DISPLAY INVISIBLE (-1330 4600);
FORCEPROP 2 LAST CDS_SEC 1
J 0
(-1325 4700);
PAINT MONO (-1325 4700);
DISPLAY INVISIBLE (-1325 4700);
FORCEPROP 2 LAST $SEC 1
J 0
(-1325 4700);
PAINT MONO (-1325 4700);
DISPLAY INVISIBLE (-1325 4700);
FORCEPROP 1 LAST PATH I27
J 0
(-1325 4650);
DISPLAY 0.978723 (-1325 4650);
PAINT WHITE (-1325 4650);
DISPLAY INVISIBLE (-1325 4650);
FORCEPROP 2 LAST ROOM PVCCIO_CPU1
J 0
(-1325 4650);
DISPLAY 1.361702 (-1325 4650);
PAINT ORANGE (-1325 4650);
DISPLAY INVISIBLE (-1325 4650);
FORCEADD PVCCIO_CPU1..1
(-2050 4875);
FORCEPROP 3 LASTPIN (-2050 4825) SIG_NAME PVCCIO_CPU1\g
J 0
(-2040 4835);
DISPLAY 0.659574 (-2040 4835);
PAINT MONO (-2040 4835);
DISPLAY INVISIBLE (-2040 4835);
FORCEPROP 1 LAST HDL_POWER PVCCIO_CPU1
J 1
(-2050 4925);
DISPLAY 0.872340 (-2050 4925);
PAINT GREEN (-2050 4925);
DISPLAY INVISIBLE (-2050 4925);
FORCEPROP 1 LAST BODY_TYPE PLUMBING
J 0
(-2095 4832);
DISPLAY 0.340426 (-2095 4832);
PAINT GREEN (-2095 4832);
DISPLAY INVISIBLE (-2095 4832);
FORCEPROP 2 LAST CDS_LIB mstr_symbols
J 0
(-2050 4875);
PAINT ORANGE (-2050 4875);
DISPLAY INVISIBLE (-2050 4875);
FORCEPROP 1 LAST VOLTAGE 1.1V
J 0
(-2095 4832);
DISPLAY 0.340426 (-2095 4832);
PAINT SKYBLUE (-2095 4832);
DISPLAY INVISIBLE (-2095 4832);
FORCEPROP 1 LAST PATH I28
J 0
(-2000 4900);
DISPLAY 0.872340 (-2000 4900);
PAINT AQUA (-2000 4900);
DISPLAY INVISIBLE (-2000 4900);
FORCEADD OFFPAGE..2
(2775 3125);
FORCEPROP 2 LAST $XR0 193 
J 0
(2964 3125);
DISPLAY 0.638298 (2964 3125);
PAINT MONO (2964 3125);
FORCEPROP 2 LAST $XR1 206 
J 0
(3084 3125);
DISPLAY 0.638298 (3084 3125);
PAINT MONO (3084 3125);
FORCEPROP 2 LAST $XR2 55 
J 0
(3204 3125);
DISPLAY 0.638298 (3204 3125);
PAINT MONO (3204 3125);
FORCEPROP 1 LAST COMMENT_BODY TRUE
J 0
(2730 3030);
DISPLAY 1.170213 (2730 3030);
PAINT GREEN (2730 3030);
DISPLAY INVISIBLE (2730 3030);
FORCEPROP 2 LAST ROOM PVCCIO_CPU1
J 0
(2350 3200);
DISPLAY 1.361702 (2350 3200);
PAINT ORANGE (2350 3200);
DISPLAY INVISIBLE (2350 3200);
FORCEPROP 2 LAST CDS_LIB mstr_standard
J 0
(2775 3125);
PAINT ORANGE (2775 3125);
DISPLAY INVISIBLE (2775 3125);
FORCEPROP 2 LAST PATH I3
J 0
(2950 3200);
DISPLAY 1.021277 (2950 3200);
PAINT ORANGE (2950 3200);
DISPLAY INVISIBLE (2950 3200);
FORCEPROP 1 LAST OFFPAGE TRUE
J 0
(3100 3000);
DISPLAY 1.170213 (3100 3000);
PAINT GREEN (3100 3000);
DISPLAY INVISIBLE (3100 3000);
FORCEADD RES..2
(-2050 4425);
FORCEPROP 1 LAST PACK_TYPE 0402
J 0
(-2010 4250);
DISPLAY 0.617021 (-2010 4250);
PAINT SKYBLUE (-2010 4250);
FORCEPROP 1 LASTPIN (-2050 4325) $PN 2
J 0
(-2045 4335);
DISPLAY 0.617021 (-2045 4335);
PAINT ORANGE (-2045 4335);
FORCEPROP 1 LAST MATERIAL EMPTY
J 0
(-2010 4350);
DISPLAY 0.617021 (-2010 4350);
PAINT RED (-2010 4350);
FORCEPROP 1 LAST TOLERANCE 1%
J 0
(-2005 4450);
DISPLAY 0.617021 (-2005 4450);
PAINT SKYBLUE (-2005 4450);
FORCEPROP 1 LASTPIN (-2050 4525) $PN 1
J 0
(-2045 4487);
DISPLAY 0.617021 (-2045 4487);
PAINT ORANGE (-2045 4487);
FORCEPROP 1 LAST WATTAGE 1/16W
J 0
(-2010 4400);
DISPLAY 0.617021 (-2010 4400);
PAINT SKYBLUE (-2010 4400);
FORCEPROP 1 LAST VALUE 110
J 0
(-2005 4500);
DISPLAY 0.617021 (-2005 4500);
PAINT SKYBLUE (-2005 4500);
FORCEPROP 1 LAST LOCATION R6P33
J 0
(-2005 4550);
DISPLAY 0.617021 (-2005 4550);
PAINT AQUA (-2005 4550);
FORCEPROP 1 LAST PART_NUMBER G21796-203
J 0
(-2010 4300);
DISPLAY 0.617021 (-2010 4300);
PAINT BLUE (-2010 4300);
FORCEPROP 2 LAST CDS_LIB mstr_discrete
J 0
(-2050 4425);
PAINT ORANGE (-2050 4425);
DISPLAY INVISIBLE (-2050 4425);
FORCEPROP 2 LAST CDS_LOCATION R6P33
J 0
(-2005 4550);
DISPLAY 0.617021 (-2005 4550);
PAINT AQUA (-2005 4550);
DISPLAY INVISIBLE (-2005 4550);
FORCEPROP 2 LAST ROOM PVCCIO_CPU1
J 0
(-2000 4600);
DISPLAY 1.361702 (-2000 4600);
PAINT ORANGE (-2000 4600);
DISPLAY INVISIBLE (-2000 4600);
FORCEPROP 1 LAST PATH I30
J 0
(-2000 4600);
DISPLAY 0.978723 (-2000 4600);
PAINT WHITE (-2000 4600);
DISPLAY INVISIBLE (-2000 4600);
FORCEPROP 2 LAST SEC 1
J 0
(-2000 4675);
PAINT MONO (-2000 4675);
DISPLAY INVISIBLE (-2000 4675);
FORCEPROP 2 LAST SEC_TYPE 0402
J 0
(-2000 4675);
DISPLAY 1.021277 (-2000 4675);
PAINT ORANGE (-2000 4675);
DISPLAY INVISIBLE (-2000 4675);
FORCEADD RES..2
(-2425 4700);
FORCEPROP 1 LAST PACK_TYPE 0402
J 0
(-2385 4525);
DISPLAY 0.617021 (-2385 4525);
PAINT SKYBLUE (-2385 4525);
FORCEPROP 1 LAST PART_NUMBER G21796-160
J 0
(-2385 4575);
DISPLAY 0.617021 (-2385 4575);
PAINT BLUE (-2385 4575);
FORCEPROP 1 LASTPIN (-2425 4800) $PN 1
J 0
(-2420 4762);
DISPLAY 0.617021 (-2420 4762);
PAINT ORANGE (-2420 4762);
FORCEPROP 1 LASTPIN (-2425 4600) $PN 2
J 0
(-2420 4610);
DISPLAY 0.617021 (-2420 4610);
PAINT ORANGE (-2420 4610);
FORCEPROP 1 LAST TOLERANCE 1%
J 0
(-2380 4725);
DISPLAY 0.617021 (-2380 4725);
PAINT SKYBLUE (-2380 4725);
FORCEPROP 1 LAST WATTAGE 1/16W
J 0
(-2385 4675);
DISPLAY 0.617021 (-2385 4675);
PAINT SKYBLUE (-2385 4675);
FORCEPROP 1 LAST MATERIAL CHIP
J 0
(-2385 4625);
DISPLAY 0.617021 (-2385 4625);
PAINT SKYBLUE (-2385 4625);
FORCEPROP 1 LAST VALUE 100.0K
J 0
(-2380 4775);
DISPLAY 0.617021 (-2380 4775);
PAINT SKYBLUE (-2380 4775);
FORCEPROP 1 LAST LOCATION R4D60
J 0
(-2380 4825);
DISPLAY 0.617021 (-2380 4825);
PAINT AQUA (-2380 4825);
FORCEPROP 2 LAST CDS_LOCATION R4D60
J 0
(-2380 4825);
DISPLAY 0.617021 (-2380 4825);
PAINT AQUA (-2380 4825);
DISPLAY INVISIBLE (-2380 4825);
FORCEPROP 2 LAST CDS_LIB mstr_discrete
J 0
(-2425 4700);
PAINT ORANGE (-2425 4700);
DISPLAY INVISIBLE (-2425 4700);
FORCEPROP 2 LAST ROOM PVCCIO_CPU1
J 0
(-2375 4875);
DISPLAY 1.361702 (-2375 4875);
PAINT ORANGE (-2375 4875);
DISPLAY INVISIBLE (-2375 4875);
FORCEPROP 1 LAST PATH I31
J 0
(-2375 4875);
DISPLAY 0.978723 (-2375 4875);
PAINT WHITE (-2375 4875);
DISPLAY INVISIBLE (-2375 4875);
FORCEPROP 2 LAST SEC 1
J 0
(-2375 4925);
DISPLAY 0.680851 (-2375 4925);
PAINT MONO (-2375 4925);
DISPLAY INVISIBLE (-2375 4925);
FORCEPROP 2 LAST SEC_TYPE 0402
J 0
(-2375 4925);
DISPLAY 1.021277 (-2375 4925);
PAINT ORANGE (-2375 4925);
DISPLAY INVISIBLE (-2375 4925);
FORCEADD RES..2
(-2425 4250);
FORCEPROP 1 LAST PACK_TYPE 0402
J 0
(-2385 4075);
DISPLAY 0.617021 (-2385 4075);
PAINT SKYBLUE (-2385 4075);
FORCEPROP 1 LAST TOLERANCE 1%
J 0
(-2380 4275);
DISPLAY 0.617021 (-2380 4275);
PAINT SKYBLUE (-2380 4275);
FORCEPROP 1 LASTPIN (-2425 4150) $PN 2
J 0
(-2420 4160);
DISPLAY 0.617021 (-2420 4160);
PAINT ORANGE (-2420 4160);
FORCEPROP 1 LASTPIN (-2425 4350) $PN 1
J 0
(-2420 4312);
DISPLAY 0.617021 (-2420 4312);
PAINT ORANGE (-2420 4312);
FORCEPROP 1 LAST WATTAGE 1/16W
J 0
(-2385 4225);
DISPLAY 0.617021 (-2385 4225);
PAINT SKYBLUE (-2385 4225);
FORCEPROP 1 LAST MATERIAL CHIP
J 0
(-2385 4175);
DISPLAY 0.617021 (-2385 4175);
PAINT SKYBLUE (-2385 4175);
FORCEPROP 1 LAST VALUE 1.5K
J 0
(-2380 4325);
DISPLAY 0.617021 (-2380 4325);
PAINT SKYBLUE (-2380 4325);
FORCEPROP 1 LAST PART_NUMBER G21796-003
J 0
(-2385 4125);
DISPLAY 0.617021 (-2385 4125);
PAINT BLUE (-2385 4125);
FORCEPROP 1 LAST LOCATION R4D57
J 0
(-2380 4375);
DISPLAY 0.617021 (-2380 4375);
PAINT AQUA (-2380 4375);
FORCEPROP 2 LAST CDS_LIB mstr_discrete
J 0
(-2425 4250);
PAINT ORANGE (-2425 4250);
DISPLAY INVISIBLE (-2425 4250);
FORCEPROP 2 LAST ROOM PVCCIO_CPU1
J 0
(-2375 4425);
DISPLAY 1.361702 (-2375 4425);
PAINT ORANGE (-2375 4425);
DISPLAY INVISIBLE (-2375 4425);
FORCEPROP 1 LAST PATH I32
J 0
(-2375 4425);
DISPLAY 0.978723 (-2375 4425);
PAINT WHITE (-2375 4425);
DISPLAY INVISIBLE (-2375 4425);
FORCEPROP 2 LAST CDS_LOCATION R4D57
J 0
(-2380 4375);
DISPLAY 0.617021 (-2380 4375);
PAINT AQUA (-2380 4375);
DISPLAY INVISIBLE (-2380 4375);
FORCEPROP 2 LAST SEC 1
J 0
(-2375 4475);
DISPLAY 0.680851 (-2375 4475);
PAINT MONO (-2375 4475);
DISPLAY INVISIBLE (-2375 4475);
FORCEPROP 2 LAST SEC_TYPE 0402
J 0
(-2375 4475);
DISPLAY 1.021277 (-2375 4475);
PAINT ORANGE (-2375 4475);
DISPLAY INVISIBLE (-2375 4475);
FORCEADD CAP..1
R 2
(-2650 4250);
FORCEPROP 1 LAST PACK_TYPE 0402LF
J 2
(-2700 4050);
DISPLAY 0.617021 (-2700 4050);
PAINT SKYBLUE (-2700 4050);
FORCEPROP 1 LAST VALUE 1000PF
J 2
(-2700 4300);
DISPLAY 0.617021 (-2700 4300);
PAINT SKYBLUE (-2700 4300);
FORCEPROP 1 LAST PART_NUMBER A36096-046
J 2
(-2700 4100);
DISPLAY 0.617021 (-2700 4100);
PAINT BLUE (-2700 4100);
FORCEPROP 1 LAST LOCATION C4D40
J 2
(-2700 4350);
DISPLAY 0.617021 (-2700 4350);
PAINT AQUA (-2700 4350);
FORCEPROP 1 LASTPIN (-2650 4150) $PN 2
J 2
(-2660 4130);
DISPLAY 0.617021 (-2660 4130);
PAINT ORANGE (-2660 4130);
FORCEPROP 1 LAST MATERIAL X7R
J 2
(-2700 4150);
DISPLAY 0.617021 (-2700 4150);
PAINT SKYBLUE (-2700 4150);
FORCEPROP 1 LAST VOLTAGE 50V
J 2
(-2700 4250);
DISPLAY 0.617021 (-2700 4250);
PAINT SKYBLUE (-2700 4250);
FORCEPROP 1 LAST TOLERANCE 10%
J 2
(-2700 4200);
DISPLAY 0.617021 (-2700 4200);
PAINT SKYBLUE (-2700 4200);
FORCEPROP 1 LASTPIN (-2650 4350) $PN 1
J 2
(-2660 4330);
DISPLAY 0.617021 (-2660 4330);
PAINT ORANGE (-2660 4330);
FORCEPROP 2 LAST CDS_LIB mstr_discrete
J 2
(-2650 4250);
PAINT ORANGE (-2650 4250);
DISPLAY INVISIBLE (-2650 4250);
FORCEPROP 2 LAST CDS_LOCATION C4D40
J 2
(-2700 4350);
DISPLAY 0.617021 (-2700 4350);
PAINT AQUA (-2700 4350);
DISPLAY INVISIBLE (-2700 4350);
FORCEPROP 2 LAST SEC 1
J 0
(-2700 4475);
DISPLAY 0.680851 (-2700 4475);
PAINT MONO (-2700 4475);
DISPLAY INVISIBLE (-2700 4475);
FORCEPROP 2 LAST SEC_TYPE 0402LF
J 0
(-2700 4475);
DISPLAY 1.021277 (-2700 4475);
PAINT ORANGE (-2700 4475);
DISPLAY INVISIBLE (-2700 4475);
FORCEPROP 1 LAST PATH I33
J 2
(-2700 4400);
DISPLAY 0.978723 (-2700 4400);
PAINT WHITE (-2700 4400);
DISPLAY INVISIBLE (-2700 4400);
FORCEPROP 2 LAST ROOM PVCCIO_CPU1
J 0
(-2700 4400);
DISPLAY 1.361702 (-2700 4400);
PAINT ORANGE (-2700 4400);
DISPLAY INVISIBLE (-2700 4400);
FORCEADD OFFPAGE..2
R 2
(-3250 4425);
FORCEPROP 2 LAST $XR0 213 
J 0
(-3505 4425);
DISPLAY 0.638298 (-3505 4425);
PAINT MONO (-3505 4425);
FORCEPROP 2 LAST ROOM PVCCIO_CPU1
J 0
(-3800 4500);
DISPLAY 1.361702 (-3800 4500);
PAINT ORANGE (-3800 4500);
DISPLAY INVISIBLE (-3800 4500);
FORCEPROP 1 LAST OFFPAGE TRUE
J 2
(-3575 4300);
DISPLAY 1.170213 (-3575 4300);
PAINT GREEN (-3575 4300);
DISPLAY INVISIBLE (-3575 4300);
FORCEPROP 2 LAST PATH I34
J 0
(-3200 4500);
DISPLAY 1.021277 (-3200 4500);
PAINT ORANGE (-3200 4500);
DISPLAY INVISIBLE (-3200 4500);
FORCEPROP 1 LAST COMMENT_BODY TRUE
J 2
(-3205 4330);
DISPLAY 1.170213 (-3205 4330);
PAINT GREEN (-3205 4330);
DISPLAY INVISIBLE (-3205 4330);
FORCEPROP 2 LAST CDS_LIB mstr_standard
J 2
(-3250 4425);
PAINT ORANGE (-3250 4425);
DISPLAY INVISIBLE (-3250 4425);
FORCEADD CAP_A..1
(-250 4150);
FORCEPROP 1 LAST PACK_TYPE 0402V
J 0
(-200 3950);
DISPLAY 0.617021 (-200 3950);
PAINT SKYBLUE (-200 3950);
FORCEPROP 1 LAST MATERIAL X7R
J 0
(-200 4050);
DISPLAY 0.617021 (-200 4050);
PAINT SKYBLUE (-200 4050);
FORCEPROP 1 LAST VOLTAGE 16V
J 0
(-200 4150);
DISPLAY 0.617021 (-200 4150);
PAINT SKYBLUE (-200 4150);
FORCEPROP 1 LAST TOLERANCE 10%
J 0
(-200 4100);
DISPLAY 0.617021 (-200 4100);
PAINT SKYBLUE (-200 4100);
FORCEPROP 1 LAST VALUE 0.1UF
J 0
(-200 4200);
DISPLAY 0.617021 (-200 4200);
PAINT SKYBLUE (-200 4200);
FORCEPROP 1 LAST LOCATION C4D38
J 0
(-200 4250);
DISPLAY 0.617021 (-200 4250);
PAINT AQUA (-200 4250);
FORCEPROP 1 LAST PART_NUMBER A36096-030
J 0
(-200 4000);
DISPLAY 0.617021 (-200 4000);
PAINT BLUE (-200 4000);
FORCEPROP 1 LASTPIN (-250 4050) $PN 2
J 0
(-240 4030);
DISPLAY 0.787234 (-240 4030);
PAINT ORANGE (-240 4030);
DISPLAY INVISIBLE (-240 4030);
FORCEPROP 1 LASTPIN (-250 4250) $PN 1
J 0
(-240 4230);
DISPLAY 0.787234 (-240 4230);
PAINT ORANGE (-240 4230);
DISPLAY INVISIBLE (-240 4230);
FORCEPROP 2 LAST CDS_LIB dev_discrete
J 0
(-250 4150);
PAINT ORANGE (-250 4150);
DISPLAY INVISIBLE (-250 4150);
FORCEPROP 2 LAST CDS_LOCATION C4D38
J 0
(-200 4250);
DISPLAY 0.617021 (-200 4250);
PAINT AQUA (-200 4250);
DISPLAY INVISIBLE (-200 4250);
FORCEPROP 1 LAST PATH I35
J 0
(-200 4300);
DISPLAY 0.978723 (-200 4300);
PAINT WHITE (-200 4300);
DISPLAY INVISIBLE (-200 4300);
FORCEPROP 2 LAST ROOM PVCCIO_CPU1
J 0
(-200 4300);
DISPLAY 1.361702 (-200 4300);
PAINT ORANGE (-200 4300);
DISPLAY INVISIBLE (-200 4300);
FORCEPROP 2 LAST CDS_SEC 1
J 0
(-200 4350);
PAINT MONO (-200 4350);
DISPLAY INVISIBLE (-200 4350);
FORCEPROP 2 LAST $SEC 1
J 0
(-200 4350);
PAINT MONO (-200 4350);
DISPLAY INVISIBLE (-200 4350);
FORCEADD GND..1
(-250 3950);
FORCEPROP 3 LASTPIN (-250 4000) SIG_NAME GND\g
J 0
(-240 4010);
DISPLAY 0.659574 (-240 4010);
PAINT MONO (-240 4010);
DISPLAY INVISIBLE (-240 4010);
FORCEPROP 2 LAST ROOM PVCCIO_CPU1
J 0
(-825 4025);
DISPLAY 1.361702 (-825 4025);
PAINT ORANGE (-825 4025);
DISPLAY INVISIBLE (-825 4025);
FORCEPROP 1 LAST BODY_TYPE PLUMBING
J 0
(-295 3907);
DISPLAY 0.340426 (-295 3907);
PAINT GREEN (-295 3907);
DISPLAY INVISIBLE (-295 3907);
FORCEPROP 1 LAST PATH I36
J 0
(-175 3950);
DISPLAY 0.872340 (-175 3950);
PAINT AQUA (-175 3950);
DISPLAY INVISIBLE (-175 3950);
FORCEPROP 1 LAST SIZE 1B
J 0
(-175 3900);
DISPLAY 1.170213 (-175 3900);
PAINT AQUA (-175 3900);
DISPLAY INVISIBLE (-175 3900);
FORCEPROP 2 LAST CDS_LIB mstr_symbols
J 0
(-250 3950);
PAINT ORANGE (-250 3950);
DISPLAY INVISIBLE (-250 3950);
FORCEPROP 1 LAST VOLTAGE 0
J 0
(-250 3950);
PAINT SKYBLUE (-250 3950);
DISPLAY INVISIBLE (-250 3950);
FORCEPROP 1 LAST HDL_POWER GND
J 0
(-250 4100);
DISPLAY 1.170213 (-250 4100);
PAINT GREEN (-250 4100);
DISPLAY INVISIBLE (-250 4100);
FORCEADD RES..1
(-1175 2925);
FORCEPROP 1 LAST WATTAGE 1/16W
J 2
(-1200 2775);
DISPLAY 0.617021 (-1200 2775);
PAINT SKYBLUE (-1200 2775);
FORCEPROP 1 LAST VALUE 0.0
J 2
(-1275 2825);
DISPLAY 0.617021 (-1275 2825);
PAINT SKYBLUE (-1275 2825);
FORCEPROP 1 LAST PART_NUMBER G21497-005
J 0
(-1325 2875);
DISPLAY 0.617021 (-1325 2875);
PAINT BLUE (-1325 2875);
FORCEPROP 1 LAST MATERIAL CHIP
J 0
(-1175 2775);
DISPLAY 0.617021 (-1175 2775);
PAINT SKYBLUE (-1175 2775);
FORCEPROP 1 LAST TOLERANCE 5%
J 0
(-1225 2825);
DISPLAY 0.617021 (-1225 2825);
PAINT SKYBLUE (-1225 2825);
FORCEPROP 1 LAST LOCATION R4D54
J 0
(-1225 2975);
DISPLAY 0.617021 (-1225 2975);
PAINT AQUA (-1225 2975);
FORCEPROP 1 LAST PACK_TYPE 0402
J 0
(-1100 2825);
DISPLAY 0.617021 (-1100 2825);
PAINT SKYBLUE (-1100 2825);
FORCEPROP 2 LAST CDS_LIB mstr_discrete
J 0
(-1175 2925);
PAINT ORANGE (-1175 2925);
DISPLAY INVISIBLE (-1175 2925);
FORCEPROP 2 LAST CDS_LOCATION R4D54
J 0
(-1225 2975);
DISPLAY 0.617021 (-1225 2975);
PAINT AQUA (-1225 2975);
DISPLAY INVISIBLE (-1225 2975);
FORCEPROP 1 LASTPIN (-1275 2925) $PN 1
J 0
(-1263 2937);
DISPLAY 0.787234 (-1263 2937);
PAINT ORANGE (-1263 2937);
DISPLAY INVISIBLE (-1263 2937);
FORCEPROP 1 LASTPIN (-1075 2925) $PN 2
J 0
(-1113 2937);
DISPLAY 0.787234 (-1113 2937);
PAINT ORANGE (-1113 2937);
DISPLAY INVISIBLE (-1113 2937);
FORCEPROP 2 LAST ROOM PVCCIO_CPU1
J 0
(-1225 3025);
DISPLAY 1.361702 (-1225 3025);
PAINT ORANGE (-1225 3025);
DISPLAY INVISIBLE (-1225 3025);
FORCEPROP 1 LAST PATH I37
J 0
(-1225 3075);
DISPLAY 0.978723 (-1225 3075);
PAINT WHITE (-1225 3075);
DISPLAY INVISIBLE (-1225 3075);
FORCEPROP 2 LAST $SEC 1
J 0
(-1225 3125);
PAINT MONO (-1225 3125);
DISPLAY INVISIBLE (-1225 3125);
FORCEPROP 2 LAST CDS_SEC 1
J 0
(-1225 3125);
PAINT MONO (-1225 3125);
DISPLAY INVISIBLE (-1225 3125);
FORCEADD RES..1
(-1175 2425);
FORCEPROP 1 LAST WATTAGE 1/16W
J 2
(-1200 2275);
DISPLAY 0.617021 (-1200 2275);
PAINT SKYBLUE (-1200 2275);
FORCEPROP 1 LAST VALUE 20.0
J 2
(-1200 2325);
DISPLAY 0.617021 (-1200 2325);
PAINT SKYBLUE (-1200 2325);
FORCEPROP 1 LAST MATERIAL CHIP
J 0
(-1175 2275);
DISPLAY 0.617021 (-1175 2275);
PAINT SKYBLUE (-1175 2275);
FORCEPROP 1 LAST PACK_TYPE 0402
J 0
(-1175 2225);
DISPLAY 0.617021 (-1175 2225);
PAINT SKYBLUE (-1175 2225);
FORCEPROP 1 LAST TOLERANCE 1%
J 0
(-1175 2325);
DISPLAY 0.617021 (-1175 2325);
PAINT SKYBLUE (-1175 2325);
FORCEPROP 1 LAST LOCATION R4D44
J 0
(-1225 2475);
DISPLAY 0.617021 (-1225 2475);
PAINT AQUA (-1225 2475);
FORCEPROP 1 LAST PART_NUMBER G21796-173
J 0
(-1225 2525);
DISPLAY 0.617021 (-1225 2525);
PAINT BLUE (-1225 2525);
FORCEPROP 1 LASTPIN (-1275 2425) $PN 1
J 0
(-1263 2437);
DISPLAY 0.787234 (-1263 2437);
PAINT ORANGE (-1263 2437);
DISPLAY INVISIBLE (-1263 2437);
FORCEPROP 2 LAST CDS_LOCATION R4D44
J 0
(-1225 2475);
DISPLAY 0.617021 (-1225 2475);
PAINT AQUA (-1225 2475);
DISPLAY INVISIBLE (-1225 2475);
FORCEPROP 2 LAST CDS_LIB mstr_discrete
J 0
(-1175 2425);
PAINT ORANGE (-1175 2425);
DISPLAY INVISIBLE (-1175 2425);
FORCEPROP 1 LASTPIN (-1075 2425) $PN 2
J 0
(-1113 2437);
DISPLAY 0.787234 (-1113 2437);
PAINT ORANGE (-1113 2437);
DISPLAY INVISIBLE (-1113 2437);
FORCEPROP 2 LAST ROOM PVCCIO_CPU1
J 0
(-1225 2525);
DISPLAY 1.361702 (-1225 2525);
PAINT ORANGE (-1225 2525);
DISPLAY INVISIBLE (-1225 2525);
FORCEPROP 1 LAST PATH I38
J 0
(-1225 2575);
DISPLAY 0.978723 (-1225 2575);
PAINT WHITE (-1225 2575);
DISPLAY INVISIBLE (-1225 2575);
FORCEPROP 2 LAST CDS_SEC 1
J 0
(-1225 2625);
PAINT MONO (-1225 2625);
DISPLAY INVISIBLE (-1225 2625);
FORCEPROP 2 LAST $SEC 1
J 0
(-1225 2625);
PAINT MONO (-1225 2625);
DISPLAY INVISIBLE (-1225 2625);
FORCEADD RES..1
(-1500 2375);
FORCEPROP 1 LAST WATTAGE 1/16W
J 2
(-1525 2225);
DISPLAY 0.617021 (-1525 2225);
PAINT SKYBLUE (-1525 2225);
FORCEPROP 1 LAST VALUE 20.0
J 2
(-1525 2275);
DISPLAY 0.617021 (-1525 2275);
PAINT SKYBLUE (-1525 2275);
FORCEPROP 1 LAST PART_NUMBER G21796-173
J 0
(-1550 2475);
DISPLAY 0.617021 (-1550 2475);
PAINT BLUE (-1550 2475);
FORCEPROP 1 LAST LOCATION R4D43
J 0
(-1550 2425);
DISPLAY 0.617021 (-1550 2425);
PAINT AQUA (-1550 2425);
FORCEPROP 1 LAST MATERIAL CHIP
J 0
(-1500 2225);
DISPLAY 0.617021 (-1500 2225);
PAINT SKYBLUE (-1500 2225);
FORCEPROP 1 LAST TOLERANCE 1%
J 0
(-1500 2275);
DISPLAY 0.617021 (-1500 2275);
PAINT SKYBLUE (-1500 2275);
FORCEPROP 1 LAST PACK_TYPE 0402
J 0
(-1375 2225);
DISPLAY 0.617021 (-1375 2225);
PAINT SKYBLUE (-1375 2225);
FORCEPROP 1 LASTPIN (-1600 2375) $PN 1
J 0
(-1588 2387);
DISPLAY 0.787234 (-1588 2387);
PAINT ORANGE (-1588 2387);
DISPLAY INVISIBLE (-1588 2387);
FORCEPROP 2 LAST ROOM PVCCIO_CPU1
J 0
(-1550 2475);
DISPLAY 1.361702 (-1550 2475);
PAINT ORANGE (-1550 2475);
DISPLAY INVISIBLE (-1550 2475);
FORCEPROP 1 LAST PATH I39
J 0
(-1550 2525);
DISPLAY 0.978723 (-1550 2525);
PAINT WHITE (-1550 2525);
DISPLAY INVISIBLE (-1550 2525);
FORCEPROP 2 LAST CDS_LOCATION R4D43
J 0
(-1550 2425);
DISPLAY 0.617021 (-1550 2425);
PAINT AQUA (-1550 2425);
DISPLAY INVISIBLE (-1550 2425);
FORCEPROP 2 LAST $SEC 1
J 0
(-1550 2575);
PAINT MONO (-1550 2575);
DISPLAY INVISIBLE (-1550 2575);
FORCEPROP 2 LAST CDS_SEC 1
J 0
(-1550 2575);
PAINT MONO (-1550 2575);
DISPLAY INVISIBLE (-1550 2575);
FORCEPROP 1 LASTPIN (-1400 2375) $PN 2
J 0
(-1438 2387);
DISPLAY 0.787234 (-1438 2387);
PAINT ORANGE (-1438 2387);
DISPLAY INVISIBLE (-1438 2387);
FORCEPROP 2 LAST CDS_LIB mstr_discrete
J 0
(-1500 2375);
PAINT ORANGE (-1500 2375);
DISPLAY INVISIBLE (-1500 2375);
FORCEADD RES..2
(-850 1325);
FORCEPROP 1 LASTPIN (-850 1225) $PN 2
J 0
(-845 1235);
DISPLAY 0.617021 (-845 1235);
PAINT ORANGE (-845 1235);
FORCEPROP 1 LASTPIN (-850 1425) $PN 1
J 0
(-845 1387);
DISPLAY 0.617021 (-845 1387);
PAINT ORANGE (-845 1387);
FORCEPROP 1 LAST WATTAGE 1/16W
J 0
(-810 1300);
DISPLAY 0.617021 (-810 1300);
PAINT SKYBLUE (-810 1300);
FORCEPROP 1 LAST MATERIAL CHIP
J 0
(-810 1250);
DISPLAY 0.617021 (-810 1250);
PAINT SKYBLUE (-810 1250);
FORCEPROP 1 LAST PACK_TYPE 0402
J 0
(-810 1150);
DISPLAY 0.617021 (-810 1150);
PAINT SKYBLUE (-810 1150);
FORCEPROP 1 LAST TOLERANCE 1%
J 0
(-805 1350);
DISPLAY 0.617021 (-805 1350);
PAINT SKYBLUE (-805 1350);
FORCEPROP 1 LAST VALUE 3.16K
J 0
(-805 1400);
DISPLAY 0.617021 (-805 1400);
PAINT SKYBLUE (-805 1400);
FORCEPROP 1 LAST PART_NUMBER G21796-043
J 0
(-810 1200);
DISPLAY 0.617021 (-810 1200);
PAINT BLUE (-810 1200);
FORCEPROP 1 LAST LOCATION R4D64
J 0
(-805 1450);
DISPLAY 0.617021 (-805 1450);
PAINT AQUA (-805 1450);
FORCEPROP 2 LAST CDS_LIB mstr_discrete
J 0
(-850 1325);
PAINT ORANGE (-850 1325);
DISPLAY INVISIBLE (-850 1325);
FORCEPROP 0 LAST SEC 1
J 0
(-800 1500);
DISPLAY 0.680851 (-800 1500);
PAINT MONO (-800 1500);
DISPLAY INVISIBLE (-800 1500);
FORCEPROP 2 LAST CDS_LOCATION R4D64
J 0
(-805 1450);
DISPLAY 0.617021 (-805 1450);
PAINT AQUA (-805 1450);
DISPLAY INVISIBLE (-805 1450);
FORCEPROP 1 LAST PATH I42
J 0
(-800 1500);
DISPLAY 0.978723 (-800 1500);
PAINT WHITE (-800 1500);
DISPLAY INVISIBLE (-800 1500);
FORCEPROP 0 LAST ROOM PVCCIO_CPU1
J 0
(-800 1550);
DISPLAY 1.021277 (-800 1550);
PAINT ORANGE (-800 1550);
DISPLAY INVISIBLE (-800 1550);
FORCEPROP 2 LAST SEC_TYPE 0402
J 0
(-800 1550);
DISPLAY 1.021277 (-800 1550);
PAINT ORANGE (-800 1550);
DISPLAY INVISIBLE (-800 1550);
FORCEPROP 0 LAST BOM_COST PROC_VRD_PVCCIO_CPU1
J 0
(-800 1650);
DISPLAY 1.021277 (-800 1650);
PAINT ORANGE (-800 1650);
DISPLAY INVISIBLE (-800 1650);
FORCEADD GND..1
(-850 750);
FORCEPROP 3 LASTPIN (-850 800) SIG_NAME GND\g
J 0
(-840 810);
DISPLAY 0.659574 (-840 810);
PAINT MONO (-840 810);
DISPLAY INVISIBLE (-840 810);
FORCEPROP 2 LAST ROOM PVCCIO_CPU1
J 0
(-1425 825);
DISPLAY 1.361702 (-1425 825);
PAINT ORANGE (-1425 825);
DISPLAY INVISIBLE (-1425 825);
FORCEPROP 1 LAST SIZE 1B
J 0
(-775 700);
DISPLAY 1.170213 (-775 700);
PAINT AQUA (-775 700);
DISPLAY INVISIBLE (-775 700);
FORCEPROP 1 LAST BODY_TYPE PLUMBING
J 0
(-895 707);
DISPLAY 0.340426 (-895 707);
PAINT GREEN (-895 707);
DISPLAY INVISIBLE (-895 707);
FORCEPROP 1 LAST PATH I44
J 0
(-775 750);
DISPLAY 0.872340 (-775 750);
PAINT AQUA (-775 750);
DISPLAY INVISIBLE (-775 750);
FORCEPROP 2 LAST CDS_LIB mstr_symbols
J 0
(-850 750);
PAINT ORANGE (-850 750);
DISPLAY INVISIBLE (-850 750);
FORCEPROP 1 LAST VOLTAGE 0
J 0
(-850 750);
PAINT SKYBLUE (-850 750);
DISPLAY INVISIBLE (-850 750);
FORCEPROP 1 LAST HDL_POWER GND
J 0
(-850 900);
DISPLAY 1.170213 (-850 900);
PAINT GREEN (-850 900);
DISPLAY INVISIBLE (-850 900);
FORCEADD GND..1
(-950 2025);
FORCEPROP 3 LASTPIN (-950 2075) SIG_NAME GND\g
J 0
(-940 2085);
DISPLAY 0.659574 (-940 2085);
PAINT MONO (-940 2085);
DISPLAY INVISIBLE (-940 2085);
FORCEPROP 1 LAST BODY_TYPE PLUMBING
J 0
(-995 1982);
DISPLAY 0.340426 (-995 1982);
PAINT GREEN (-995 1982);
DISPLAY INVISIBLE (-995 1982);
FORCEPROP 1 LAST SIZE 1B
J 0
(-875 1975);
DISPLAY 1.170213 (-875 1975);
PAINT AQUA (-875 1975);
DISPLAY INVISIBLE (-875 1975);
FORCEPROP 1 LAST PATH I45
J 0
(-875 2025);
DISPLAY 0.872340 (-875 2025);
PAINT AQUA (-875 2025);
DISPLAY INVISIBLE (-875 2025);
FORCEPROP 2 LAST CDS_LIB mstr_symbols
J 0
(-950 2025);
PAINT ORANGE (-950 2025);
DISPLAY INVISIBLE (-950 2025);
FORCEPROP 1 LAST VOLTAGE 0
J 0
(-950 2025);
PAINT SKYBLUE (-950 2025);
DISPLAY INVISIBLE (-950 2025);
FORCEPROP 2 LAST ROOM PVCCIO_CPU1
J 0
(-1525 2100);
DISPLAY 1.361702 (-1525 2100);
PAINT ORANGE (-1525 2100);
DISPLAY INVISIBLE (-1525 2100);
FORCEPROP 1 LAST HDL_POWER GND
J 0
(-950 2175);
DISPLAY 1.170213 (-950 2175);
PAINT GREEN (-950 2175);
DISPLAY INVISIBLE (-950 2175);
FORCEADD RES..1
(-1825 3925);
FORCEPROP 1 LAST VALUE 150.0
J 2
(-1825 4000);
DISPLAY 0.617021 (-1825 4000);
PAINT SKYBLUE (-1825 4000);
FORCEPROP 1 LASTPIN (-1925 3925) $PN 1
J 0
(-1913 3937);
DISPLAY 0.617021 (-1913 3937);
PAINT ORANGE (-1913 3937);
FORCEPROP 1 LAST PART_NUMBER G21796-009
J 0
(-1925 4050);
DISPLAY 0.617021 (-1925 4050);
PAINT BLUE (-1925 4050);
FORCEPROP 1 LAST WATTAGE 1/16W
J 2
(-1775 3950);
DISPLAY 0.617021 (-1775 3950);
PAINT SKYBLUE (-1775 3950);
FORCEPROP 1 LAST MATERIAL CHIP
J 0
(-1725 3950);
DISPLAY 0.617021 (-1725 3950);
PAINT SKYBLUE (-1725 3950);
FORCEPROP 1 LAST TOLERANCE 1%
J 0
(-1775 4000);
DISPLAY 0.617021 (-1775 4000);
PAINT SKYBLUE (-1775 4000);
FORCEPROP 1 LASTPIN (-1725 3925) $PN 2
J 0
(-1763 3937);
DISPLAY 0.617021 (-1763 3937);
PAINT ORANGE (-1763 3937);
FORCEPROP 1 LAST PACK_TYPE 0402
J 0
(-1650 4000);
DISPLAY 0.617021 (-1650 4000);
PAINT SKYBLUE (-1650 4000);
FORCEPROP 1 LAST LOCATION R4D51
J 0
(-1925 4100);
DISPLAY 0.617021 (-1925 4100);
PAINT AQUA (-1925 4100);
FORCEPROP 2 LAST CDS_LIB mstr_discrete
J 0
(-1825 3925);
PAINT ORANGE (-1825 3925);
DISPLAY INVISIBLE (-1825 3925);
FORCEPROP 1 LAST PATH I46
J 0
(-1875 4075);
DISPLAY 0.978723 (-1875 4075);
PAINT WHITE (-1875 4075);
DISPLAY INVISIBLE (-1875 4075);
FORCEPROP 2 LAST ROOM PVCCIO_CPU1
J 0
(-1925 4150);
DISPLAY 1.361702 (-1925 4150);
PAINT ORANGE (-1925 4150);
DISPLAY INVISIBLE (-1925 4150);
FORCEPROP 2 LAST CDS_LOCATION R4D51
J 0
(-1925 4100);
DISPLAY 0.617021 (-1925 4100);
PAINT AQUA (-1925 4100);
DISPLAY INVISIBLE (-1925 4100);
FORCEPROP 2 LAST SEC 1
J 0
(-1875 4150);
DISPLAY 0.680851 (-1875 4150);
PAINT MONO (-1875 4150);
DISPLAY INVISIBLE (-1875 4150);
FORCEPROP 2 LAST SEC_TYPE 0402
J 0
(-1875 4150);
DISPLAY 1.021277 (-1875 4150);
PAINT ORANGE (-1875 4150);
DISPLAY INVISIBLE (-1875 4150);
FORCEADD GND..1
(-2425 4000);
FORCEPROP 3 LASTPIN (-2425 4050) SIG_NAME GND\g
J 0
(-2415 4060);
DISPLAY 0.659574 (-2415 4060);
PAINT MONO (-2415 4060);
DISPLAY INVISIBLE (-2415 4060);
FORCEPROP 1 LAST PATH I47
J 0
(-2350 4000);
DISPLAY 0.872340 (-2350 4000);
PAINT AQUA (-2350 4000);
DISPLAY INVISIBLE (-2350 4000);
FORCEPROP 1 LAST BODY_TYPE PLUMBING
J 0
(-2470 3957);
DISPLAY 0.340426 (-2470 3957);
PAINT GREEN (-2470 3957);
DISPLAY INVISIBLE (-2470 3957);
FORCEPROP 1 LAST SIZE 1B
J 0
(-2350 3950);
DISPLAY 1.170213 (-2350 3950);
PAINT AQUA (-2350 3950);
DISPLAY INVISIBLE (-2350 3950);
FORCEPROP 2 LAST CDS_LIB mstr_symbols
J 0
(-2425 4000);
PAINT ORANGE (-2425 4000);
DISPLAY INVISIBLE (-2425 4000);
FORCEPROP 1 LAST VOLTAGE 0
J 0
(-2425 4000);
PAINT SKYBLUE (-2425 4000);
DISPLAY INVISIBLE (-2425 4000);
FORCEPROP 2 LAST ROOM PVCCIO_CPU1
J 0
(-3000 4075);
DISPLAY 1.361702 (-3000 4075);
PAINT ORANGE (-3000 4075);
DISPLAY INVISIBLE (-3000 4075);
FORCEPROP 1 LAST HDL_POWER GND
J 0
(-2425 4150);
DISPLAY 1.170213 (-2425 4150);
PAINT GREEN (-2425 4150);
DISPLAY INVISIBLE (-2425 4150);
FORCEADD GND..1
(-2650 4000);
FORCEPROP 3 LASTPIN (-2650 4050) SIG_NAME GND\g
J 0
(-2640 4060);
DISPLAY 0.659574 (-2640 4060);
PAINT MONO (-2640 4060);
DISPLAY INVISIBLE (-2640 4060);
FORCEPROP 1 LAST PATH I49
J 0
(-2575 4000);
DISPLAY 0.872340 (-2575 4000);
PAINT AQUA (-2575 4000);
DISPLAY INVISIBLE (-2575 4000);
FORCEPROP 1 LAST BODY_TYPE PLUMBING
J 0
(-2695 3957);
DISPLAY 0.340426 (-2695 3957);
PAINT GREEN (-2695 3957);
DISPLAY INVISIBLE (-2695 3957);
FORCEPROP 2 LAST CDS_LIB mstr_symbols
J 0
(-2650 4000);
PAINT ORANGE (-2650 4000);
DISPLAY INVISIBLE (-2650 4000);
FORCEPROP 1 LAST SIZE 1B
J 0
(-2575 3950);
DISPLAY 1.170213 (-2575 3950);
PAINT AQUA (-2575 3950);
DISPLAY INVISIBLE (-2575 3950);
FORCEPROP 1 LAST VOLTAGE 0
J 0
(-2650 4000);
PAINT SKYBLUE (-2650 4000);
DISPLAY INVISIBLE (-2650 4000);
FORCEPROP 2 LAST ROOM PVCCIO_CPU1
J 0
(-3225 4075);
DISPLAY 1.361702 (-3225 4075);
PAINT ORANGE (-3225 4075);
DISPLAY INVISIBLE (-3225 4075);
FORCEPROP 1 LAST HDL_POWER GND
J 0
(-2650 4150);
DISPLAY 1.170213 (-2650 4150);
PAINT GREEN (-2650 4150);
DISPLAY INVISIBLE (-2650 4150);
FORCEADD OFFPAGE..2
(2775 2975);
FORCEPROP 2 LAST $XR0 214 
J 0
(2964 2975);
DISPLAY 0.638298 (2964 2975);
PAINT MONO (2964 2975);
FORCEPROP 1 LAST COMMENT_BODY TRUE
J 0
(2730 2880);
DISPLAY 1.170213 (2730 2880);
PAINT GREEN (2730 2880);
DISPLAY INVISIBLE (2730 2880);
FORCEPROP 2 LAST CDS_LIB mstr_standard
J 0
(2775 2975);
PAINT ORANGE (2775 2975);
DISPLAY INVISIBLE (2775 2975);
FORCEPROP 2 LAST PATH I5
J 0
(2950 3050);
DISPLAY 1.021277 (2950 3050);
PAINT ORANGE (2950 3050);
DISPLAY INVISIBLE (2950 3050);
FORCEPROP 2 LAST ROOM PVCCIO_CPU1
J 0
(2350 3050);
DISPLAY 1.361702 (2350 3050);
PAINT ORANGE (2350 3050);
DISPLAY INVISIBLE (2350 3050);
FORCEPROP 1 LAST OFFPAGE TRUE
J 0
(3100 2850);
DISPLAY 1.170213 (3100 2850);
PAINT GREEN (3100 2850);
DISPLAY INVISIBLE (3100 2850);
FORCEADD OFFPAGE..1
(-2875 3925);
FORCEPROP 2 LAST $XR0 55 
J 0
(-3096 3925);
DISPLAY 0.638298 (-3096 3925);
PAINT MONO (-3096 3925);
FORCEPROP 2 LAST $XR1 193 
J 0
(-3216 3925);
DISPLAY 0.638298 (-3216 3925);
PAINT MONO (-3216 3925);
FORCEPROP 2 LAST $XR2 206 
J 0
(-3336 3925);
DISPLAY 0.638298 (-3336 3925);
PAINT MONO (-3336 3925);
FORCEPROP 2 LAST ROOM PVCCIO_CPU1
J 0
(-3425 4000);
DISPLAY 1.361702 (-3425 4000);
PAINT ORANGE (-3425 4000);
DISPLAY INVISIBLE (-3425 4000);
FORCEPROP 2 LAST PATH I50
J 0
(-2825 4000);
DISPLAY 1.021277 (-2825 4000);
PAINT ORANGE (-2825 4000);
DISPLAY INVISIBLE (-2825 4000);
FORCEPROP 2 LAST CDS_LIB mstr_standard
J 0
(-2875 3925);
PAINT ORANGE (-2875 3925);
DISPLAY INVISIBLE (-2875 3925);
FORCEPROP 1 LAST COMMENT_BODY TRUE
J 0
(-2750 3825);
DISPLAY 1.170213 (-2750 3825);
PAINT GREEN (-2750 3825);
DISPLAY INVISIBLE (-2750 3825);
FORCEPROP 1 LAST OFFPAGE TRUE
J 0
(-2550 3800);
DISPLAY 1.170213 (-2550 3800);
PAINT GREEN (-2550 3800);
DISPLAY INVISIBLE (-2550 3800);
FORCEADD OFFPAGE..1
(-2675 3375);
FORCEPROP 2 LAST $XR0 214 
J 0
(-2927 3375);
DISPLAY 0.638298 (-2927 3375);
PAINT MONO (-2927 3375);
FORCEPROP 2 LAST ROOM PVCCIO_CPU1
J 0
(-3225 3450);
DISPLAY 1.361702 (-3225 3450);
PAINT ORANGE (-3225 3450);
DISPLAY INVISIBLE (-3225 3450);
FORCEPROP 2 LAST PATH I51
J 0
(-2625 3450);
DISPLAY 1.021277 (-2625 3450);
PAINT ORANGE (-2625 3450);
DISPLAY INVISIBLE (-2625 3450);
FORCEPROP 2 LAST CDS_LIB mstr_standard
J 0
(-2675 3375);
PAINT ORANGE (-2675 3375);
DISPLAY INVISIBLE (-2675 3375);
FORCEPROP 1 LAST OFFPAGE TRUE
J 0
(-2350 3250);
DISPLAY 1.170213 (-2350 3250);
PAINT GREEN (-2350 3250);
DISPLAY INVISIBLE (-2350 3250);
FORCEPROP 1 LAST COMMENT_BODY TRUE
J 0
(-2550 3275);
DISPLAY 1.170213 (-2550 3275);
PAINT GREEN (-2550 3275);
DISPLAY INVISIBLE (-2550 3275);
FORCEADD OFFPAGE..1
(-2675 3425);
FORCEPROP 2 LAST $XR0 214 
J 0
(-2927 3425);
DISPLAY 0.638298 (-2927 3425);
PAINT MONO (-2927 3425);
FORCEPROP 2 LAST ROOM PVCCIO_CPU1
J 0
(-3225 3500);
DISPLAY 1.361702 (-3225 3500);
PAINT ORANGE (-3225 3500);
DISPLAY INVISIBLE (-3225 3500);
FORCEPROP 2 LAST PATH I52
J 0
(-2625 3500);
DISPLAY 1.021277 (-2625 3500);
PAINT ORANGE (-2625 3500);
DISPLAY INVISIBLE (-2625 3500);
FORCEPROP 2 LAST CDS_LIB mstr_standard
J 0
(-2675 3425);
PAINT ORANGE (-2675 3425);
DISPLAY INVISIBLE (-2675 3425);
FORCEPROP 1 LAST OFFPAGE TRUE
J 0
(-2350 3300);
DISPLAY 1.170213 (-2350 3300);
PAINT GREEN (-2350 3300);
DISPLAY INVISIBLE (-2350 3300);
FORCEPROP 1 LAST COMMENT_BODY TRUE
J 0
(-2550 3325);
DISPLAY 1.170213 (-2550 3325);
PAINT GREEN (-2550 3325);
DISPLAY INVISIBLE (-2550 3325);
FORCEADD OFFPAGE..1
(-2675 3125);
FORCEPROP 2 LAST $XR0 213 
J 0
(-2927 3125);
DISPLAY 0.638298 (-2927 3125);
PAINT MONO (-2927 3125);
FORCEPROP 2 LAST ROOM PVCCIO_CPU1
J 0
(-3225 3200);
DISPLAY 1.361702 (-3225 3200);
PAINT ORANGE (-3225 3200);
DISPLAY INVISIBLE (-3225 3200);
FORCEPROP 1 LAST OFFPAGE TRUE
J 0
(-2350 3000);
DISPLAY 1.170213 (-2350 3000);
PAINT GREEN (-2350 3000);
DISPLAY INVISIBLE (-2350 3000);
FORCEPROP 1 LAST COMMENT_BODY TRUE
J 0
(-2550 3025);
DISPLAY 1.170213 (-2550 3025);
PAINT GREEN (-2550 3025);
DISPLAY INVISIBLE (-2550 3025);
FORCEPROP 2 LAST PATH I53
J 0
(-2625 3200);
DISPLAY 1.021277 (-2625 3200);
PAINT ORANGE (-2625 3200);
DISPLAY INVISIBLE (-2625 3200);
FORCEPROP 2 LAST CDS_LIB mstr_standard
J 0
(-2675 3125);
PAINT ORANGE (-2675 3125);
DISPLAY INVISIBLE (-2675 3125);
FORCEADD OFFPAGE..1
(-2675 3225);
FORCEPROP 2 LAST $XR0 190 
J 0
(-2927 3225);
DISPLAY 0.638298 (-2927 3225);
PAINT MONO (-2927 3225);
FORCEPROP 2 LAST ROOM PVCCIO_CPU1
J 0
(-3225 3300);
DISPLAY 1.361702 (-3225 3300);
PAINT ORANGE (-3225 3300);
DISPLAY INVISIBLE (-3225 3300);
FORCEPROP 2 LAST CDS_LIB mstr_standard
J 0
(-2675 3225);
PAINT ORANGE (-2675 3225);
DISPLAY INVISIBLE (-2675 3225);
FORCEPROP 2 LAST PATH I54
J 0
(-2625 3300);
DISPLAY 1.021277 (-2625 3300);
PAINT ORANGE (-2625 3300);
DISPLAY INVISIBLE (-2625 3300);
FORCEPROP 1 LAST OFFPAGE TRUE
J 0
(-2350 3100);
DISPLAY 1.170213 (-2350 3100);
PAINT GREEN (-2350 3100);
DISPLAY INVISIBLE (-2350 3100);
FORCEPROP 1 LAST COMMENT_BODY TRUE
J 0
(-2550 3125);
DISPLAY 1.170213 (-2550 3125);
PAINT GREEN (-2550 3125);
DISPLAY INVISIBLE (-2550 3125);
FORCEADD OFFPAGE..1
(-2675 3275);
FORCEPROP 2 LAST $XR0 214 
J 0
(-2927 3275);
DISPLAY 0.638298 (-2927 3275);
PAINT MONO (-2927 3275);
FORCEPROP 2 LAST ROOM PVCCIO_CPU1
J 0
(-3225 3350);
DISPLAY 1.361702 (-3225 3350);
PAINT ORANGE (-3225 3350);
DISPLAY INVISIBLE (-3225 3350);
FORCEPROP 2 LAST CDS_LIB mstr_standard
J 0
(-2675 3275);
PAINT ORANGE (-2675 3275);
DISPLAY INVISIBLE (-2675 3275);
FORCEPROP 2 LAST PATH I55
J 0
(-2625 3350);
DISPLAY 1.021277 (-2625 3350);
PAINT ORANGE (-2625 3350);
DISPLAY INVISIBLE (-2625 3350);
FORCEPROP 1 LAST OFFPAGE TRUE
J 0
(-2350 3150);
DISPLAY 1.170213 (-2350 3150);
PAINT GREEN (-2350 3150);
DISPLAY INVISIBLE (-2350 3150);
FORCEPROP 1 LAST COMMENT_BODY TRUE
J 0
(-2550 3175);
DISPLAY 1.170213 (-2550 3175);
PAINT GREEN (-2550 3175);
DISPLAY INVISIBLE (-2550 3175);
FORCEADD OFFPAGE..2
R 2
(-2675 2925);
FORCEPROP 2 LAST $XR0 55 
J 0
(-2899 2925);
DISPLAY 0.638298 (-2899 2925);
PAINT MONO (-2899 2925);
FORCEPROP 2 LAST $XR1 193 
J 0
(-3019 2925);
DISPLAY 0.638298 (-3019 2925);
PAINT MONO (-3019 2925);
FORCEPROP 2 LAST $XR2 206 
J 0
(-3139 2925);
DISPLAY 0.638298 (-3139 2925);
PAINT MONO (-3139 2925);
FORCEPROP 2 LAST ROOM PVCCIO_CPU1
J 0
(-3225 3000);
DISPLAY 1.361702 (-3225 3000);
PAINT ORANGE (-3225 3000);
DISPLAY INVISIBLE (-3225 3000);
FORCEPROP 1 LAST OFFPAGE TRUE
J 2
(-3000 2800);
DISPLAY 1.170213 (-3000 2800);
PAINT GREEN (-3000 2800);
DISPLAY INVISIBLE (-3000 2800);
FORCEPROP 1 LAST COMMENT_BODY TRUE
J 2
(-2630 2830);
DISPLAY 1.170213 (-2630 2830);
PAINT GREEN (-2630 2830);
DISPLAY INVISIBLE (-2630 2830);
FORCEPROP 2 LAST CDS_LIB mstr_standard
J 0
(-2675 2925);
PAINT ORANGE (-2675 2925);
DISPLAY INVISIBLE (-2675 2925);
FORCEPROP 2 LAST PATH I57
J 0
(-2625 3000);
DISPLAY 1.021277 (-2625 3000);
PAINT ORANGE (-2625 3000);
DISPLAY INVISIBLE (-2625 3000);
FORCEADD OFFPAGE..2
R 2
(-2675 2975);
FORCEPROP 2 LAST $XR0 213 
J 0
(-2930 2975);
DISPLAY 0.638298 (-2930 2975);
PAINT MONO (-2930 2975);
FORCEPROP 2 LAST ROOM PVCCIO_CPU1
J 0
(-3225 3050);
DISPLAY 1.361702 (-3225 3050);
PAINT ORANGE (-3225 3050);
DISPLAY INVISIBLE (-3225 3050);
FORCEPROP 1 LAST OFFPAGE TRUE
J 2
(-3000 2850);
DISPLAY 1.170213 (-3000 2850);
PAINT GREEN (-3000 2850);
DISPLAY INVISIBLE (-3000 2850);
FORCEPROP 1 LAST COMMENT_BODY TRUE
J 2
(-2630 2880);
DISPLAY 1.170213 (-2630 2880);
PAINT GREEN (-2630 2880);
DISPLAY INVISIBLE (-2630 2880);
FORCEPROP 2 LAST CDS_LIB mstr_standard
J 0
(-2675 2975);
PAINT ORANGE (-2675 2975);
DISPLAY INVISIBLE (-2675 2975);
FORCEPROP 2 LAST PATH I58
J 0
(-2625 3050);
DISPLAY 1.021277 (-2625 3050);
PAINT ORANGE (-2625 3050);
DISPLAY INVISIBLE (-2625 3050);
FORCEADD OFFPAGE..2
R 2
(-2675 2375);
FORCEPROP 2 LAST $XR0 138 
J 0
(-2960 2375);
DISPLAY 0.638298 (-2960 2375);
PAINT MONO (-2960 2375);
FORCEPROP 2 LAST $XR1 159 
J 0
(-3080 2375);
DISPLAY 0.638298 (-3080 2375);
PAINT MONO (-3080 2375);
FORCEPROP 2 LAST $XR2 211 
J 0
(-3200 2375);
DISPLAY 0.638298 (-3200 2375);
PAINT MONO (-3200 2375);
FORCEPROP 2 LAST $XR3 235 
J 0
(-3320 2375);
DISPLAY 0.638298 (-3320 2375);
PAINT MONO (-3320 2375);
FORCEPROP 2 LAST $XR4 193 
J 0
(-3440 2375);
DISPLAY 0.638298 (-3440 2375);
PAINT MONO (-3440 2375);
FORCEPROP 2 LAST $XR5 194 
J 0
(-3560 2375);
DISPLAY 0.638298 (-3560 2375);
PAINT MONO (-3560 2375);
FORCEPROP 2 LAST $XR6 201 
J 0
(-3680 2375);
DISPLAY 0.638298 (-3680 2375);
PAINT MONO (-3680 2375);
FORCEPROP 2 LAST $XR7 206 
J 0
(-2960 2339);
DISPLAY 0.638298 (-2960 2339);
PAINT MONO (-2960 2339);
FORCEPROP 2 LAST $XR8 215 
J 0
(-3080 2339);
DISPLAY 0.638298 (-3080 2339);
PAINT MONO (-3080 2339);
FORCEPROP 2 LAST $XR9 218 
J 0
(-3200 2339);
DISPLAY 0.638298 (-3200 2339);
PAINT MONO (-3200 2339);
FORCEPROP 2 LAST $XR10 223 
J 0
(-3320 2339);
DISPLAY 0.638298 (-3320 2339);
PAINT MONO (-3320 2339);
FORCEPROP 2 LAST $XR11 226 
J 0
(-3440 2339);
DISPLAY 0.638298 (-3440 2339);
PAINT MONO (-3440 2339);
FORCEPROP 2 LAST ROOM PVCCIO_CPU1
J 0
(-3225 2450);
DISPLAY 1.361702 (-3225 2450);
PAINT ORANGE (-3225 2450);
DISPLAY INVISIBLE (-3225 2450);
FORCEPROP 1 LAST OFFPAGE TRUE
J 2
(-3000 2250);
DISPLAY 1.170213 (-3000 2250);
PAINT GREEN (-3000 2250);
DISPLAY INVISIBLE (-3000 2250);
FORCEPROP 1 LAST COMMENT_BODY TRUE
J 2
(-2630 2280);
DISPLAY 1.170213 (-2630 2280);
PAINT GREEN (-2630 2280);
DISPLAY INVISIBLE (-2630 2280);
FORCEPROP 2 LAST CDS_LIB mstr_standard
J 0
(-2675 2375);
PAINT ORANGE (-2675 2375);
DISPLAY INVISIBLE (-2675 2375);
FORCEPROP 2 LAST PATH I61
J 0
(-2625 2450);
DISPLAY 1.021277 (-2625 2450);
PAINT ORANGE (-2625 2450);
DISPLAY INVISIBLE (-2625 2450);
FORCEADD OFFPAGE..3
R 2
(-2675 2425);
FORCEPROP 2 LAST $XR0 138 
J 0
(-2955 2425);
DISPLAY 0.638298 (-2955 2425);
PAINT MONO (-2955 2425);
FORCEPROP 2 LAST $XR1 159 
J 0
(-3075 2425);
DISPLAY 0.638298 (-3075 2425);
PAINT MONO (-3075 2425);
FORCEPROP 2 LAST $XR2 193 
J 0
(-3195 2425);
DISPLAY 0.638298 (-3195 2425);
PAINT MONO (-3195 2425);
FORCEPROP 2 LAST $XR3 194 
J 0
(-3315 2425);
DISPLAY 0.638298 (-3315 2425);
PAINT MONO (-3315 2425);
FORCEPROP 2 LAST $XR4 201 
J 0
(-3435 2425);
DISPLAY 0.638298 (-3435 2425);
PAINT MONO (-3435 2425);
FORCEPROP 2 LAST $XR5 206 
J 0
(-3555 2425);
DISPLAY 0.638298 (-3555 2425);
PAINT MONO (-3555 2425);
FORCEPROP 2 LAST $XR6 211 
J 0
(-3675 2425);
DISPLAY 0.638298 (-3675 2425);
PAINT MONO (-3675 2425);
FORCEPROP 2 LAST $XR7 215 
J 0
(-2955 2461);
DISPLAY 0.638298 (-2955 2461);
PAINT MONO (-2955 2461);
FORCEPROP 2 LAST $XR8 218 
J 0
(-3075 2461);
DISPLAY 0.638298 (-3075 2461);
PAINT MONO (-3075 2461);
FORCEPROP 2 LAST $XR9 223 
J 0
(-3195 2461);
DISPLAY 0.638298 (-3195 2461);
PAINT MONO (-3195 2461);
FORCEPROP 2 LAST $XR10 226 
J 0
(-3315 2461);
DISPLAY 0.638298 (-3315 2461);
PAINT MONO (-3315 2461);
FORCEPROP 2 LAST $XR11 235 
J 0
(-3435 2461);
DISPLAY 0.638298 (-3435 2461);
PAINT MONO (-3435 2461);
FORCEPROP 2 LAST ROOM PVCCIO_CPU1
J 0
(-3225 2500);
DISPLAY 1.361702 (-3225 2500);
PAINT ORANGE (-3225 2500);
DISPLAY INVISIBLE (-3225 2500);
FORCEPROP 1 LAST OFFPAGE TRUE
J 2
(-3000 2300);
DISPLAY 0.872340 (-3000 2300);
PAINT GREEN (-3000 2300);
DISPLAY INVISIBLE (-3000 2300);
FORCEPROP 1 LAST COMMENT_BODY TRUE
J 2
(-2625 2325);
DISPLAY 0.872340 (-2625 2325);
PAINT GREEN (-2625 2325);
DISPLAY INVISIBLE (-2625 2325);
FORCEPROP 2 LAST CDS_LIB mstr_standard
J 0
(-2675 2425);
PAINT ORANGE (-2675 2425);
DISPLAY INVISIBLE (-2675 2425);
FORCEPROP 2 LAST PATH I62
J 0
(-2625 2500);
DISPLAY 1.021277 (-2625 2500);
PAINT ORANGE (-2625 2500);
DISPLAY INVISIBLE (-2625 2500);
FORCEADD RES..2
(2175 4050);
FORCEPROP 1 LAST PART_NUMBER G21796-026
J 0
(2215 3925);
DISPLAY 0.617021 (2215 3925);
PAINT BLUE (2215 3925);
FORCEPROP 1 LAST WATTAGE 1/16W
J 0
(2215 4025);
DISPLAY 0.617021 (2215 4025);
PAINT SKYBLUE (2215 4025);
FORCEPROP 1 LAST MATERIAL CHIP
J 0
(2215 3975);
DISPLAY 0.617021 (2215 3975);
PAINT SKYBLUE (2215 3975);
FORCEPROP 1 LAST PACK_TYPE 0402
J 0
(2215 3875);
DISPLAY 0.617021 (2215 3875);
PAINT SKYBLUE (2215 3875);
FORCEPROP 1 LAST TOLERANCE 1%
J 0
(2220 4075);
DISPLAY 0.617021 (2220 4075);
PAINT SKYBLUE (2220 4075);
FORCEPROP 1 LAST VALUE 1.00K
J 0
(2220 4125);
DISPLAY 0.617021 (2220 4125);
PAINT SKYBLUE (2220 4125);
FORCEPROP 1 LAST LOCATION R4D49
J 0
(2220 4175);
DISPLAY 0.617021 (2220 4175);
PAINT AQUA (2220 4175);
FORCEPROP 1 LASTPIN (2175 3950) $PN 2
J 0
(2180 3960);
DISPLAY 0.787234 (2180 3960);
PAINT ORANGE (2180 3960);
DISPLAY INVISIBLE (2180 3960);
FORCEPROP 2 LAST CDS_LIB mstr_discrete
J 0
(2175 4050);
PAINT ORANGE (2175 4050);
DISPLAY INVISIBLE (2175 4050);
FORCEPROP 1 LASTPIN (2175 4150) $PN 1
J 0
(2180 4112);
DISPLAY 0.787234 (2180 4112);
PAINT ORANGE (2180 4112);
DISPLAY INVISIBLE (2180 4112);
FORCEPROP 1 LAST PATH I63
J 0
(2225 4225);
DISPLAY 0.978723 (2225 4225);
PAINT WHITE (2225 4225);
DISPLAY INVISIBLE (2225 4225);
FORCEPROP 2 LAST CDS_LOCATION R4D49
J 0
(2220 4175);
DISPLAY 0.617021 (2220 4175);
PAINT AQUA (2220 4175);
DISPLAY INVISIBLE (2220 4175);
FORCEPROP 2 LAST $SEC 1
J 0
(2225 4275);
DISPLAY 0.680851 (2225 4275);
PAINT MONO (2225 4275);
DISPLAY INVISIBLE (2225 4275);
FORCEPROP 2 LAST CDS_SEC 1
J 0
(2225 4275);
DISPLAY 1.021277 (2225 4275);
PAINT ORANGE (2225 4275);
DISPLAY INVISIBLE (2225 4275);
FORCEADD RES..2
(-525 1325);
FORCEPROP 1 LAST LOCATION R4E2
J 0
(-480 1450);
DISPLAY 0.617021 (-480 1450);
PAINT AQUA (-480 1450);
FORCEPROP 1 LAST PART_NUMBER G21796-043
J 0
(-485 1200);
DISPLAY 0.617021 (-485 1200);
PAINT BLUE (-485 1200);
FORCEPROP 1 LAST VALUE 3.16K
J 0
(-480 1400);
DISPLAY 0.617021 (-480 1400);
PAINT SKYBLUE (-480 1400);
FORCEPROP 1 LAST TOLERANCE 1%
J 0
(-480 1350);
DISPLAY 0.617021 (-480 1350);
PAINT SKYBLUE (-480 1350);
FORCEPROP 1 LAST PACK_TYPE 0402
J 0
(-485 1150);
DISPLAY 0.617021 (-485 1150);
PAINT SKYBLUE (-485 1150);
FORCEPROP 1 LAST MATERIAL CHIP
J 0
(-485 1250);
DISPLAY 0.617021 (-485 1250);
PAINT SKYBLUE (-485 1250);
FORCEPROP 1 LAST WATTAGE 1/16W
J 0
(-485 1300);
DISPLAY 0.617021 (-485 1300);
PAINT SKYBLUE (-485 1300);
FORCEPROP 1 LASTPIN (-525 1425) $PN 1
J 0
(-520 1387);
DISPLAY 0.787234 (-520 1387);
PAINT ORANGE (-520 1387);
DISPLAY INVISIBLE (-520 1387);
FORCEPROP 1 LASTPIN (-525 1225) $PN 2
J 0
(-520 1235);
DISPLAY 0.787234 (-520 1235);
PAINT ORANGE (-520 1235);
DISPLAY INVISIBLE (-520 1235);
FORCEPROP 2 LAST CDS_LIB mstr_discrete
J 0
(-525 1325);
PAINT ORANGE (-525 1325);
DISPLAY INVISIBLE (-525 1325);
FORCEPROP 2 LAST CDS_LOCATION R4E2
J 0
(-480 1450);
DISPLAY 0.617021 (-480 1450);
PAINT AQUA (-480 1450);
DISPLAY INVISIBLE (-480 1450);
FORCEPROP 1 LAST PATH I65
J 0
(-475 1500);
DISPLAY 0.978723 (-475 1500);
PAINT WHITE (-475 1500);
DISPLAY INVISIBLE (-475 1500);
FORCEPROP 2 LAST CDS_SEC 1
J 0
(-475 1550);
DISPLAY 1.021277 (-475 1550);
PAINT ORANGE (-475 1550);
DISPLAY INVISIBLE (-475 1550);
FORCEPROP 2 LAST $SEC 1
J 0
(-475 1550);
DISPLAY 0.680851 (-475 1550);
PAINT MONO (-475 1550);
DISPLAY INVISIBLE (-475 1550);
FORCEADD CAP..1
(1750 2700);
FORCEPROP 1 LAST PACK_TYPE 0402LF
J 0
(1825 2500);
DISPLAY 0.617021 (1825 2500);
PAINT SKYBLUE (1825 2500);
FORCEPROP 1 LASTPIN (1750 2800) $PN 1
J 0
(1760 2780);
DISPLAY 0.617021 (1760 2780);
PAINT ORANGE (1760 2780);
FORCEPROP 1 LASTPIN (1750 2600) $PN 2
J 0
(1760 2580);
DISPLAY 0.617021 (1760 2580);
PAINT ORANGE (1760 2580);
FORCEPROP 1 LAST MATERIAL X7R
J 0
(1800 2600);
DISPLAY 0.617021 (1800 2600);
PAINT SKYBLUE (1800 2600);
FORCEPROP 1 LAST VOLTAGE 50V
J 0
(1800 2700);
DISPLAY 0.617021 (1800 2700);
PAINT SKYBLUE (1800 2700);
FORCEPROP 1 LAST LOCATION C4D33
J 0
(1800 2800);
DISPLAY 0.617021 (1800 2800);
PAINT AQUA (1800 2800);
FORCEPROP 1 LAST VALUE 1000PF
J 0
(1800 2750);
DISPLAY 0.617021 (1800 2750);
PAINT SKYBLUE (1800 2750);
FORCEPROP 1 LAST TOLERANCE 10%
J 0
(1800 2650);
DISPLAY 0.617021 (1800 2650);
PAINT SKYBLUE (1800 2650);
FORCEPROP 1 LAST PART_NUMBER A36096-046
J 0
(1800 2550);
DISPLAY 0.617021 (1800 2550);
PAINT BLUE (1800 2550);
FORCEPROP 2 LAST CDS_LIB mstr_discrete
J 0
(1750 2700);
PAINT MONO (1750 2700);
DISPLAY INVISIBLE (1750 2700);
FORCEPROP 2 LAST SEC_TYPE 0402LF
J 0
(1800 2900);
DISPLAY 1.021277 (1800 2900);
PAINT ORANGE (1800 2900);
DISPLAY INVISIBLE (1800 2900);
FORCEPROP 2 LAST SEC 1
J 0
(1800 2900);
DISPLAY 0.680851 (1800 2900);
PAINT MONO (1800 2900);
DISPLAY INVISIBLE (1800 2900);
FORCEPROP 2 LAST CDS_LOCATION C4D33
J 0
(1800 2800);
DISPLAY 0.617021 (1800 2800);
PAINT AQUA (1800 2800);
DISPLAY INVISIBLE (1800 2800);
FORCEPROP 1 LAST PATH I73
J 0
(1800 2850);
DISPLAY 0.978723 (1800 2850);
PAINT WHITE (1800 2850);
DISPLAY INVISIBLE (1800 2850);
FORCEPROP 0 LAST ROOM PVCCIO_CPU1_VR
J 0
(1800 2900);
DISPLAY 1.021277 (1800 2900);
PAINT ORANGE (1800 2900);
DISPLAY INVISIBLE (1800 2900);
FORCEADD GND..1
(1750 2500);
FORCEPROP 3 LASTPIN (1750 2550) SIG_NAME GND\g
J 0
(1760 2560);
DISPLAY 0.659574 (1760 2560);
PAINT MONO (1760 2560);
DISPLAY INVISIBLE (1760 2560);
FORCEPROP 2 LAST ROOM PVCCIO_CPU1
J 0
(1175 2575);
DISPLAY 1.361702 (1175 2575);
PAINT ORANGE (1175 2575);
DISPLAY INVISIBLE (1175 2575);
FORCEPROP 1 LAST PATH I74
J 0
(1825 2500);
DISPLAY 0.872340 (1825 2500);
PAINT AQUA (1825 2500);
DISPLAY INVISIBLE (1825 2500);
FORCEPROP 1 LAST BODY_TYPE PLUMBING
J 0
(1705 2457);
DISPLAY 0.340426 (1705 2457);
PAINT GREEN (1705 2457);
DISPLAY INVISIBLE (1705 2457);
FORCEPROP 1 LAST SIZE 1B
J 0
(1825 2450);
DISPLAY 1.170213 (1825 2450);
PAINT AQUA (1825 2450);
DISPLAY INVISIBLE (1825 2450);
FORCEPROP 2 LAST CDS_LIB mstr_symbols
J 0
(1750 2500);
PAINT MONO (1750 2500);
DISPLAY INVISIBLE (1750 2500);
FORCEPROP 1 LAST VOLTAGE 0
J 0
(1750 2500);
PAINT SKYBLUE (1750 2500);
DISPLAY INVISIBLE (1750 2500);
FORCEPROP 1 LAST HDL_POWER GND
J 0
(1750 2650);
DISPLAY 1.170213 (1750 2650);
PAINT GREEN (1750 2650);
DISPLAY INVISIBLE (1750 2650);
FORCEADD OFFPAGE..1
R 2
(2800 1750);
FORCEPROP 2 LAST $XR0 213 
J 0
(2986 1750);
DISPLAY 0.638298 (2986 1750);
PAINT MONO (2986 1750);
FORCEPROP 1 LAST OFFPAGE TRUE
J 2
(2475 1625);
DISPLAY 1.170213 (2475 1625);
PAINT GREEN (2475 1625);
DISPLAY INVISIBLE (2475 1625);
FORCEPROP 2 LAST ROOM PVCCIO_CPU1
J 0
(2375 1825);
DISPLAY 1.361702 (2375 1825);
PAINT ORANGE (2375 1825);
DISPLAY INVISIBLE (2375 1825);
FORCEPROP 1 LAST COMMENT_BODY TRUE
J 2
(2675 1650);
DISPLAY 1.170213 (2675 1650);
PAINT GREEN (2675 1650);
DISPLAY INVISIBLE (2675 1650);
FORCEPROP 2 LAST CDS_LIB mstr_standard
J 2
(2800 1750);
PAINT ORANGE (2800 1750);
DISPLAY INVISIBLE (2800 1750);
FORCEPROP 2 LAST PATH I8
J 0
(2975 1825);
DISPLAY 1.021277 (2975 1825);
PAINT ORANGE (2975 1825);
DISPLAY INVISIBLE (2975 1825);
FORCEADD CAP..1
(-2075 1725);
FORCEPROP 1 LASTPIN (-2075 1825) $PN 1
J 0
(-2065 1805);
DISPLAY 0.617021 (-2065 1805);
PAINT ORANGE (-2065 1805);
FORCEPROP 1 LASTPIN (-2075 1625) $PN 2
J 0
(-2065 1605);
DISPLAY 0.617021 (-2065 1605);
PAINT ORANGE (-2065 1605);
FORCEPROP 1 LAST MATERIAL X7R
J 0
(-1900 1725);
DISPLAY 0.617021 (-1900 1725);
PAINT SKYBLUE (-1900 1725);
FORCEPROP 1 LAST VOLTAGE 50V
J 0
(-2025 1725);
DISPLAY 0.617021 (-2025 1725);
PAINT SKYBLUE (-2025 1725);
FORCEPROP 1 LAST PACK_TYPE 0402LF
J 0
(-2025 1625);
DISPLAY 0.617021 (-2025 1625);
PAINT SKYBLUE (-2025 1625);
FORCEPROP 1 LAST TOLERANCE 10%
J 0
(-1850 1775);
DISPLAY 0.617021 (-1850 1775);
PAINT SKYBLUE (-1850 1775);
FORCEPROP 1 LAST VALUE 220PF
J 0
(-2025 1775);
DISPLAY 0.617021 (-2025 1775);
PAINT SKYBLUE (-2025 1775);
FORCEPROP 1 LAST PART_NUMBER A36096-050
J 0
(-2025 1675);
DISPLAY 0.617021 (-2025 1675);
PAINT BLUE (-2025 1675);
FORCEPROP 1 LAST LOCATION C4D44
J 0
(-2025 1825);
DISPLAY 0.617021 (-2025 1825);
PAINT AQUA (-2025 1825);
FORCEPROP 2 LAST CDS_LIB mstr_discrete
J 0
(-2075 1725);
PAINT ORANGE (-2075 1725);
DISPLAY INVISIBLE (-2075 1725);
FORCEPROP 2 LAST ROOM PVCCIO_CPU1
J 0
(-2025 1875);
DISPLAY 1.361702 (-2025 1875);
PAINT ORANGE (-2025 1875);
DISPLAY INVISIBLE (-2025 1875);
FORCEPROP 1 LAST PATH I83
J 0
(-2025 1875);
DISPLAY 0.978723 (-2025 1875);
PAINT WHITE (-2025 1875);
DISPLAY INVISIBLE (-2025 1875);
FORCEPROP 2 LAST CDS_LOCATION C4D44
J 0
(-2025 1825);
DISPLAY 0.617021 (-2025 1825);
PAINT AQUA (-2025 1825);
DISPLAY INVISIBLE (-2025 1825);
FORCEPROP 2 LAST SEC 1
J 0
(-2025 1950);
DISPLAY 0.680851 (-2025 1950);
PAINT MONO (-2025 1950);
DISPLAY INVISIBLE (-2025 1950);
FORCEPROP 2 LAST SEC_TYPE 0402LF
J 0
(-2025 1950);
DISPLAY 1.021277 (-2025 1950);
PAINT ORANGE (-2025 1950);
DISPLAY INVISIBLE (-2025 1950);
FORCEADD RES..1
(-2325 1925);
FORCEPROP 1 LASTPIN (-2425 1925) $PN 1
J 0
(-2413 1937);
DISPLAY 0.617021 (-2413 1937);
PAINT ORANGE (-2413 1937);
FORCEPROP 1 LAST WATTAGE 1/16W
J 2
(-2325 1775);
DISPLAY 0.617021 (-2325 1775);
PAINT SKYBLUE (-2325 1775);
FORCEPROP 1 LAST TOLERANCE 1%
J 0
(-2400 1825);
DISPLAY 0.617021 (-2400 1825);
PAINT SKYBLUE (-2400 1825);
FORCEPROP 1 LAST VALUE 10.0
J 2
(-2425 1825);
DISPLAY 0.617021 (-2425 1825);
PAINT SKYBLUE (-2425 1825);
FORCEPROP 1 LAST PART_NUMBER G21796-066
J 0
(-2475 1875);
DISPLAY 0.617021 (-2475 1875);
PAINT BLUE (-2475 1875);
FORCEPROP 1 LAST LOCATION R4E7
J 0
(-2375 1975);
DISPLAY 0.617021 (-2375 1975);
PAINT AQUA (-2375 1975);
FORCEPROP 1 LAST MATERIAL CHIP
J 0
(-2300 1775);
DISPLAY 0.617021 (-2300 1775);
PAINT SKYBLUE (-2300 1775);
FORCEPROP 1 LASTPIN (-2225 1925) $PN 2
J 0
(-2263 1937);
DISPLAY 0.617021 (-2263 1937);
PAINT ORANGE (-2263 1937);
FORCEPROP 1 LAST PACK_TYPE 0402
J 0
(-2300 1825);
DISPLAY 0.617021 (-2300 1825);
PAINT SKYBLUE (-2300 1825);
FORCEPROP 2 LAST CDS_LOCATION R4E7
J 0
(-2375 1975);
DISPLAY 0.617021 (-2375 1975);
PAINT AQUA (-2375 1975);
DISPLAY INVISIBLE (-2375 1975);
FORCEPROP 2 LAST CDS_LIB mstr_discrete
J 0
(-2325 1925);
PAINT ORANGE (-2325 1925);
DISPLAY INVISIBLE (-2325 1925);
FORCEPROP 2 LAST ROOM PVCCIO_CPU1
J 0
(-2250 2025);
DISPLAY 1.361702 (-2250 2025);
PAINT ORANGE (-2250 2025);
DISPLAY INVISIBLE (-2250 2025);
FORCEPROP 1 LAST PATH I84
J 0
(-2375 2075);
DISPLAY 0.978723 (-2375 2075);
PAINT WHITE (-2375 2075);
DISPLAY INVISIBLE (-2375 2075);
FORCEPROP 2 LAST SEC 1
J 0
(-2375 2150);
DISPLAY 0.680851 (-2375 2150);
PAINT MONO (-2375 2150);
DISPLAY INVISIBLE (-2375 2150);
FORCEPROP 2 LAST SEC_TYPE 0402
J 0
(-2375 2150);
DISPLAY 1.021277 (-2375 2150);
PAINT ORANGE (-2375 2150);
DISPLAY INVISIBLE (-2375 2150);
FORCEADD OFFPAGE..1
(-3175 1925);
FORCEPROP 2 LAST $XR0 214 
J 0
(-3427 1925);
DISPLAY 0.638298 (-3427 1925);
PAINT MONO (-3427 1925);
FORCEPROP 2 LAST PATH I86
J 0
(-3450 1975);
DISPLAY 1.021277 (-3450 1975);
PAINT ORANGE (-3450 1975);
DISPLAY INVISIBLE (-3450 1975);
FORCEPROP 2 LAST CDS_LIB mstr_standard
J 0
(-3175 1925);
PAINT ORANGE (-3175 1925);
DISPLAY INVISIBLE (-3175 1925);
FORCEPROP 1 LAST COMMENT_BODY TRUE
J 0
(-3050 1825);
DISPLAY 1.170213 (-3050 1825);
PAINT GREEN (-3050 1825);
DISPLAY INVISIBLE (-3050 1825);
FORCEPROP 1 LAST OFFPAGE TRUE
J 0
(-2850 1800);
DISPLAY 1.170213 (-2850 1800);
PAINT GREEN (-2850 1800);
DISPLAY INVISIBLE (-2850 1800);
FORCEPROP 2 LAST ROOM PVCCIO_CPU1
J 0
(-3725 2000);
DISPLAY 1.361702 (-3725 2000);
PAINT ORANGE (-3725 2000);
DISPLAY INVISIBLE (-3725 2000);
FORCEADD OFFPAGE..1
(-3175 1525);
FORCEPROP 2 LAST $XR0 214 
J 0
(-3427 1525);
DISPLAY 0.638298 (-3427 1525);
PAINT MONO (-3427 1525);
FORCEPROP 2 LAST ROOM PVCCIO_CPU1
J 0
(-3725 1600);
DISPLAY 1.361702 (-3725 1600);
PAINT ORANGE (-3725 1600);
DISPLAY INVISIBLE (-3725 1600);
FORCEPROP 2 LAST CDS_LIB mstr_standard
J 0
(-3175 1525);
PAINT ORANGE (-3175 1525);
DISPLAY INVISIBLE (-3175 1525);
FORCEPROP 2 LAST PATH I87
J 0
(-3450 1575);
DISPLAY 1.021277 (-3450 1575);
PAINT ORANGE (-3450 1575);
DISPLAY INVISIBLE (-3450 1575);
FORCEPROP 1 LAST COMMENT_BODY TRUE
J 0
(-3050 1425);
DISPLAY 1.170213 (-3050 1425);
PAINT GREEN (-3050 1425);
DISPLAY INVISIBLE (-3050 1425);
FORCEPROP 1 LAST OFFPAGE TRUE
J 0
(-2850 1400);
DISPLAY 1.170213 (-2850 1400);
PAINT GREEN (-2850 1400);
DISPLAY INVISIBLE (-2850 1400);
FORCEADD CAP_A..1
(2425 1575);
FORCEPROP 1 LASTPIN (2425 1475) $PN 2
J 0
(2435 1455);
DISPLAY 0.617021 (2435 1455);
PAINT ORANGE (2435 1455);
FORCEPROP 1 LASTPIN (2425 1675) $PN 1
J 0
(2435 1655);
DISPLAY 0.617021 (2435 1655);
PAINT ORANGE (2435 1655);
FORCEPROP 1 LAST MATERIAL X6S
J 0
(2475 1475);
DISPLAY 0.617021 (2475 1475);
PAINT SKYBLUE (2475 1475);
FORCEPROP 1 LAST VOLTAGE 6.3V
J 0
(2475 1575);
DISPLAY 0.617021 (2475 1575);
PAINT SKYBLUE (2475 1575);
FORCEPROP 1 LAST PACK_TYPE 0402V
J 0
(2475 1375);
DISPLAY 0.617021 (2475 1375);
PAINT SKYBLUE (2475 1375);
FORCEPROP 1 LAST TOLERANCE 10%
J 0
(2475 1525);
DISPLAY 0.617021 (2475 1525);
PAINT SKYBLUE (2475 1525);
FORCEPROP 1 LAST VALUE 1.0UF
J 0
(2475 1625);
DISPLAY 0.617021 (2475 1625);
PAINT SKYBLUE (2475 1625);
FORCEPROP 1 LAST PART_NUMBER D97712-004
J 0
(2475 1425);
DISPLAY 0.617021 (2475 1425);
PAINT BLUE (2475 1425);
FORCEPROP 1 LAST LOCATION C4D31
J 0
(2475 1675);
DISPLAY 0.617021 (2475 1675);
PAINT AQUA (2475 1675);
FORCEPROP 2 LAST CDS_LIB dev_discrete
J 0
(2425 1575);
PAINT ORANGE (2425 1575);
DISPLAY INVISIBLE (2425 1575);
FORCEPROP 2 LAST CDS_LOCATION C4D31
J 0
(2475 1675);
DISPLAY 0.617021 (2475 1675);
PAINT AQUA (2475 1675);
DISPLAY INVISIBLE (2475 1675);
FORCEPROP 2 LAST CDS_SEC 1
J 0
(2475 1725);
PAINT ORANGE (2475 1725);
DISPLAY INVISIBLE (2475 1725);
FORCEPROP 1 LAST PATH I9
J 0
(2475 1725);
DISPLAY 0.978723 (2475 1725);
PAINT WHITE (2475 1725);
DISPLAY INVISIBLE (2475 1725);
FORCEPROP 2 LAST ROOM PVCCIO_CPU1
J 0
(2475 1725);
DISPLAY 1.361702 (2475 1725);
PAINT ORANGE (2475 1725);
DISPLAY INVISIBLE (2475 1725);
FORCEPROP 2 LAST SEC_TYPE 0402V
J 0
(2475 1775);
DISPLAY 1.021277 (2475 1775);
PAINT ORANGE (2475 1775);
DISPLAY INVISIBLE (2475 1775);
FORCEPROP 2 LAST SEC 1
J 0
(2475 1775);
DISPLAY 0.680851 (2475 1775);
PAINT MONO (2475 1775);
DISPLAY INVISIBLE (2475 1775);
FORCEADD RES..1
(-1925 3225);
FORCEPROP 1 LAST WATTAGE 1/16W
J 2
(-1950 3075);
DISPLAY 0.617021 (-1950 3075);
PAINT SKYBLUE (-1950 3075);
FORCEPROP 1 LAST VALUE 0.0
J 2
(-2025 3125);
DISPLAY 0.617021 (-2025 3125);
PAINT SKYBLUE (-2025 3125);
FORCEPROP 1 LAST PART_NUMBER G21497-005
J 0
(-2075 3175);
DISPLAY 0.617021 (-2075 3175);
PAINT BLUE (-2075 3175);
FORCEPROP 1 LAST MATERIAL CHIP
J 0
(-1925 3075);
DISPLAY 0.617021 (-1925 3075);
PAINT SKYBLUE (-1925 3075);
FORCEPROP 1 LAST TOLERANCE 5%
J 0
(-1975 3125);
DISPLAY 0.617021 (-1975 3125);
PAINT SKYBLUE (-1975 3125);
FORCEPROP 1 LAST LOCATION R6P41
J 0
(-1975 3275);
DISPLAY 0.617021 (-1975 3275);
PAINT AQUA (-1975 3275);
FORCEPROP 1 LAST PACK_TYPE 0402
J 0
(-1850 3125);
DISPLAY 0.617021 (-1850 3125);
PAINT SKYBLUE (-1850 3125);
FORCEPROP 2 LAST CDS_LOCATION R6P41
J 0
(-1975 3275);
DISPLAY 0.617021 (-1975 3275);
PAINT AQUA (-1975 3275);
DISPLAY INVISIBLE (-1975 3275);
FORCEPROP 2 LAST CDS_LIB mstr_discrete
J 0
(-1925 3225);
PAINT ORANGE (-1925 3225);
DISPLAY INVISIBLE (-1925 3225);
FORCEPROP 1 LASTPIN (-2025 3225) $PN 1
J 0
(-2013 3237);
DISPLAY 0.787234 (-2013 3237);
PAINT ORANGE (-2013 3237);
DISPLAY INVISIBLE (-2013 3237);
FORCEPROP 1 LASTPIN (-1825 3225) $PN 2
J 0
(-1863 3237);
DISPLAY 0.787234 (-1863 3237);
PAINT ORANGE (-1863 3237);
DISPLAY INVISIBLE (-1863 3237);
FORCEPROP 2 LAST ROOM PVCCIN_CPU0_VR
J 0
(-1975 3325);
DISPLAY 1.361702 (-1975 3325);
PAINT ORANGE (-1975 3325);
DISPLAY INVISIBLE (-1975 3325);
FORCEPROP 1 LAST PATH I90
J 0
(-1975 3375);
DISPLAY 0.978723 (-1975 3375);
PAINT WHITE (-1975 3375);
DISPLAY INVISIBLE (-1975 3375);
FORCEPROP 2 LAST $SEC 1
J 0
(-1975 3425);
PAINT MONO (-1975 3425);
DISPLAY INVISIBLE (-1975 3425);
FORCEPROP 2 LAST CDS_SEC 1
J 0
(-1975 3425);
PAINT MONO (-1975 3425);
DISPLAY INVISIBLE (-1975 3425);
FORCEADD RES..2
(-1025 4275);
FORCEPROP 1 LAST TOLERANCE 1%
J 0
(-980 4300);
DISPLAY 0.617021 (-980 4300);
PAINT SKYBLUE (-980 4300);
FORCEPROP 1 LAST WATTAGE 1/16W
J 0
(-985 4250);
DISPLAY 0.617021 (-985 4250);
PAINT SKYBLUE (-985 4250);
FORCEPROP 1 LAST PACK_TYPE 0402
J 0
(-985 4100);
DISPLAY 0.617021 (-985 4100);
PAINT SKYBLUE (-985 4100);
FORCEPROP 1 LAST MATERIAL EMPTY
J 0
(-985 4200);
DISPLAY 0.617021 (-985 4200);
PAINT RED (-985 4200);
FORCEPROP 1 LAST VALUE 100.0K
J 0
(-980 4350);
DISPLAY 0.617021 (-980 4350);
PAINT SKYBLUE (-980 4350);
FORCEPROP 1 LAST LOCATION R6P40
J 0
(-980 4400);
DISPLAY 0.617021 (-980 4400);
PAINT AQUA (-980 4400);
FORCEPROP 1 LAST PART_NUMBER G21796-010
J 0
(-985 4150);
DISPLAY 0.617021 (-985 4150);
PAINT BLUE (-985 4150);
FORCEPROP 2 LAST CDS_LIB mstr_discrete
J 0
(-1025 4275);
PAINT ORANGE (-1025 4275);
DISPLAY INVISIBLE (-1025 4275);
FORCEPROP 1 LASTPIN (-1025 4175) $PN 2
J 0
(-1020 4185);
DISPLAY 0.787234 (-1020 4185);
PAINT ORANGE (-1020 4185);
DISPLAY INVISIBLE (-1020 4185);
FORCEPROP 1 LASTPIN (-1025 4375) $PN 1
J 0
(-1020 4337);
DISPLAY 0.787234 (-1020 4337);
PAINT ORANGE (-1020 4337);
DISPLAY INVISIBLE (-1020 4337);
FORCEPROP 0 LAST ROOM BMC
J 0
(-975 4500);
DISPLAY 0.617021 (-975 4500);
PAINT ORANGE (-975 4500);
DISPLAY INVISIBLE (-975 4500);
FORCEPROP 1 LAST PATH I91
J 0
(-975 4450);
DISPLAY 0.978723 (-975 4450);
PAINT WHITE (-975 4450);
DISPLAY INVISIBLE (-975 4450);
FORCEPROP 2 LAST CDS_LOCATION R6P40
J 0
(-980 4400);
DISPLAY 0.617021 (-980 4400);
PAINT AQUA (-980 4400);
DISPLAY INVISIBLE (-980 4400);
FORCEPROP 2 LAST $SEC 1
J 0
(-975 4500);
PAINT MONO (-975 4500);
DISPLAY INVISIBLE (-975 4500);
FORCEPROP 2 LAST CDS_SEC 1
J 0
(-975 4500);
PAINT MONO (-975 4500);
DISPLAY INVISIBLE (-975 4500);
FORCEPROP 0 LAST BOM_COST SM_CONTROLLER
J 0
(-975 4600);
DISPLAY 1.021277 (-975 4600);
PAINT ORANGE (-975 4600);
DISPLAY INVISIBLE (-975 4600);
FORCEADD UNIVERSAL_POWER..1
(-2425 4975);
FORCEPROP 3 LASTPIN (-2425 4925) SIG_NAME VR_FET_SW_P12V_STBY_PVCCIN_CPU0\g
J 0
(-2415 4935);
DISPLAY 0.659574 (-2415 4935);
PAINT MONO (-2415 4935);
DISPLAY INVISIBLE (-2415 4935);
FORCEPROP 1 LAST HDL_POWER VR_FET_SW_P12V_STBY_PVCCIN_CPU0
J 1
(-2325 5025);
DISPLAY 0.617021 (-2325 5025);
PAINT GREEN (-2325 5025);
FORCEPROP 1 LAST PATH I92
J 0
(-2375 5000);
DISPLAY 0.872340 (-2375 5000);
PAINT AQUA (-2375 5000);
DISPLAY INVISIBLE (-2375 5000);
FORCEPROP 2 LAST CDS_LIB mstr_symbols
J 0
(-2425 4975);
PAINT ORANGE (-2425 4975);
DISPLAY INVISIBLE (-2425 4975);
FORCEADD RES..1
(-2425 3675);
FORCEPROP 1 LAST WATTAGE 1/16W
J 2
(-2450 3525);
DISPLAY 0.617021 (-2450 3525);
PAINT SKYBLUE (-2450 3525);
FORCEPROP 1 LAST VALUE 0.0
J 2
(-2525 3575);
DISPLAY 0.617021 (-2525 3575);
PAINT SKYBLUE (-2525 3575);
FORCEPROP 1 LAST PART_NUMBER G21497-005
J 0
(-2575 3625);
DISPLAY 0.617021 (-2575 3625);
PAINT BLUE (-2575 3625);
FORCEPROP 1 LAST MATERIAL CHIP
J 0
(-2425 3525);
DISPLAY 0.617021 (-2425 3525);
PAINT SKYBLUE (-2425 3525);
FORCEPROP 1 LAST PACK_TYPE 0402
J 0
(-2350 3575);
DISPLAY 0.617021 (-2350 3575);
PAINT SKYBLUE (-2350 3575);
FORCEPROP 1 LAST TOLERANCE 5%
J 0
(-2475 3575);
DISPLAY 0.617021 (-2475 3575);
PAINT SKYBLUE (-2475 3575);
FORCEPROP 1 LAST LOCATION R4D45
J 0
(-2475 3725);
DISPLAY 0.617021 (-2475 3725);
PAINT AQUA (-2475 3725);
FORCEPROP 1 LASTPIN (-2525 3675) $PN 1
J 0
(-2513 3687);
DISPLAY 0.787234 (-2513 3687);
PAINT ORANGE (-2513 3687);
DISPLAY INVISIBLE (-2513 3687);
FORCEPROP 2 LAST CDS_LOCATION R4D45
J 0
(-2475 3725);
DISPLAY 0.617021 (-2475 3725);
PAINT AQUA (-2475 3725);
DISPLAY INVISIBLE (-2475 3725);
FORCEPROP 2 LAST ROOM PVCCIN_CPU0_VR
J 0
(-2475 3775);
DISPLAY 1.361702 (-2475 3775);
PAINT ORANGE (-2475 3775);
DISPLAY INVISIBLE (-2475 3775);
FORCEPROP 1 LASTPIN (-2325 3675) $PN 2
J 0
(-2363 3687);
DISPLAY 0.787234 (-2363 3687);
PAINT ORANGE (-2363 3687);
DISPLAY INVISIBLE (-2363 3687);
FORCEPROP 2 LAST CDS_LIB mstr_discrete
J 0
(-2425 3675);
PAINT ORANGE (-2425 3675);
DISPLAY INVISIBLE (-2425 3675);
FORCEPROP 1 LAST PATH I94
J 0
(-2475 3825);
DISPLAY 0.978723 (-2475 3825);
PAINT WHITE (-2475 3825);
DISPLAY INVISIBLE (-2475 3825);
FORCEPROP 2 LAST $SEC 1
J 0
(-2475 3875);
PAINT MONO (-2475 3875);
DISPLAY INVISIBLE (-2475 3875);
FORCEPROP 2 LAST CDS_SEC 1
J 0
(-2475 3875);
PAINT MONO (-2475 3875);
DISPLAY INVISIBLE (-2475 3875);
FORCEADD OFFPAGE..1
(-3175 3675);
FORCEPROP 2 LAST $XR0 213 
J 0
(-3427 3675);
DISPLAY 0.638298 (-3427 3675);
PAINT MONO (-3427 3675);
FORCEPROP 2 LAST ROOM PVCCIO_CPU1
J 0
(-3725 3750);
DISPLAY 1.361702 (-3725 3750);
PAINT ORANGE (-3725 3750);
DISPLAY INVISIBLE (-3725 3750);
FORCEPROP 2 LAST PATH I95
J 0
(-3125 3750);
DISPLAY 1.021277 (-3125 3750);
PAINT ORANGE (-3125 3750);
DISPLAY INVISIBLE (-3125 3750);
FORCEPROP 2 LAST CDS_LIB mstr_standard
J 0
(-3175 3675);
PAINT ORANGE (-3175 3675);
DISPLAY INVISIBLE (-3175 3675);
FORCEPROP 1 LAST COMMENT_BODY TRUE
J 0
(-3050 3575);
DISPLAY 1.170213 (-3050 3575);
PAINT GREEN (-3050 3575);
DISPLAY INVISIBLE (-3050 3575);
FORCEPROP 1 LAST OFFPAGE TRUE
J 0
(-2850 3550);
DISPLAY 1.170213 (-2850 3550);
PAINT GREEN (-2850 3550);
DISPLAY INVISIBLE (-2850 3550);
FORCEADD PXE1110B..1
(175 2825);
FORCEPROP 2 LASTPIN (-275 2025) $PN 33
J 2
(-285 2035);
DISPLAY 0.617021 (-285 2035);
PAINT ORANGE (-285 2035);
FORCEPROP 2 LASTPIN (-275 2175) $PN 25
J 2
(-285 2185);
DISPLAY 0.617021 (-285 2185);
PAINT ORANGE (-285 2185);
FORCEPROP 2 LASTPIN (-275 2125) $PN 26
J 2
(-285 2135);
DISPLAY 0.617021 (-285 2135);
PAINT ORANGE (-285 2135);
FORCEPROP 2 LASTPIN (-275 2075) $PN 36
J 2
(-285 2085);
DISPLAY 0.617021 (-285 2085);
PAINT ORANGE (-285 2085);
FORCEPROP 2 LASTPIN (-275 2275) $PN 34
J 2
(-285 2285);
DISPLAY 0.617021 (-285 2285);
PAINT ORANGE (-285 2285);
FORCEPROP 2 LASTPIN (-275 2375) $PN 7
J 2
(-285 2385);
DISPLAY 0.617021 (-285 2385);
PAINT ORANGE (-285 2385);
FORCEPROP 2 LASTPIN (-275 2425) $PN 6
J 2
(-285 2435);
DISPLAY 0.617021 (-285 2435);
PAINT ORANGE (-285 2435);
FORCEPROP 2 LASTPIN (-275 2525) $PN 30
J 2
(-285 2535);
DISPLAY 0.617021 (-285 2535);
PAINT ORANGE (-285 2535);
FORCEPROP 2 LASTPIN (-275 2575) $PN 29
J 2
(-285 2585);
DISPLAY 0.617021 (-285 2585);
PAINT ORANGE (-285 2585);
FORCEPROP 2 LASTPIN (-275 2775) $PN 8
J 2
(-285 2785);
DISPLAY 0.617021 (-285 2785);
PAINT ORANGE (-285 2785);
FORCEPROP 2 LASTPIN (-275 2675) $PN 19
J 2
(-285 2685);
DISPLAY 0.617021 (-285 2685);
PAINT ORANGE (-285 2685);
FORCEPROP 2 LASTPIN (-275 2625) $PN 20
J 2
(-285 2635);
DISPLAY 0.617021 (-285 2635);
PAINT ORANGE (-285 2635);
FORCEPROP 2 LASTPIN (-275 2925) $PN 16
J 2
(-285 2935);
DISPLAY 0.617021 (-285 2935);
PAINT ORANGE (-285 2935);
FORCEPROP 2 LASTPIN (-275 2975) $PN 40
J 2
(-285 2985);
DISPLAY 0.617021 (-285 2985);
PAINT ORANGE (-285 2985);
FORCEPROP 2 LASTPIN (-275 3125) $PN 37
J 2
(-285 3135);
DISPLAY 0.617021 (-285 3135);
PAINT ORANGE (-285 3135);
FORCEPROP 2 LASTPIN (-275 3075) $PN 38
J 2
(-285 3085);
DISPLAY 0.617021 (-285 3085);
PAINT ORANGE (-285 3085);
FORCEPROP 2 LASTPIN (-275 3225) $PN 10
J 2
(-285 3235);
DISPLAY 0.617021 (-285 3235);
PAINT ORANGE (-285 3235);
FORCEPROP 2 LASTPIN (-275 3275) $PN 35
J 2
(-285 3285);
DISPLAY 0.617021 (-285 3285);
PAINT ORANGE (-285 3285);
FORCEPROP 2 LASTPIN (-275 3525) $PN 15
J 2
(-285 3535);
DISPLAY 0.617021 (-285 3535);
PAINT ORANGE (-285 3535);
FORCEPROP 2 LASTPIN (-275 3375) $PN 22
J 2
(-285 3385);
DISPLAY 0.617021 (-285 3385);
PAINT ORANGE (-285 3385);
FORCEPROP 2 LASTPIN (-275 3425) $PN 21
J 2
(-285 3435);
DISPLAY 0.617021 (-285 3435);
PAINT ORANGE (-285 3435);
FORCEPROP 2 LASTPIN (-275 3575) $PN 39
J 2
(-285 3585);
DISPLAY 0.617021 (-285 3585);
PAINT ORANGE (-285 3585);
FORCEPROP 1 LAST MATERIAL IC
J 0
(-225 3700);
DISPLAY 0.617021 (-225 3700);
PAINT SKYBLUE (-225 3700);
FORCEPROP 1 LAST LOCATION EU4D5
J 0
(-225 3750);
DISPLAY 0.617021 (-225 3750);
PAINT AQUA (-225 3750);
FORCEPROP 1 LAST PART_NUMBER H89187-001
J 0
(-225 1925);
DISPLAY 0.617021 (-225 1925);
PAINT BLUE (-225 1925);
FORCEPROP 2 LASTPIN (625 2075) $PN 27
J 0
(635 2085);
DISPLAY 0.617021 (635 2085);
PAINT ORANGE (635 2085);
FORCEPROP 2 LASTPIN (625 2125) $PN 23
J 0
(635 2135);
DISPLAY 0.617021 (635 2135);
PAINT ORANGE (635 2135);
FORCEPROP 2 LASTPIN (625 2275) $PN 41
J 0
(635 2285);
DISPLAY 0.617021 (635 2285);
PAINT ORANGE (635 2285);
FORCEPROP 2 LASTPIN (625 2475) $PN 4
J 0
(635 2485);
DISPLAY 0.617021 (635 2485);
PAINT ORANGE (635 2485);
FORCEPROP 2 LASTPIN (625 2425) $PN 2
J 0
(635 2435);
DISPLAY 0.617021 (635 2435);
PAINT ORANGE (635 2435);
FORCEPROP 2 LASTPIN (625 2375) $PN 1
J 0
(635 2385);
DISPLAY 0.617021 (635 2385);
PAINT ORANGE (635 2385);
FORCEPROP 2 LASTPIN (625 2525) $PN 24
J 0
(635 2535);
DISPLAY 0.617021 (635 2535);
PAINT ORANGE (635 2535);
FORCEPROP 2 LASTPIN (625 2575) $PN 28
J 0
(635 2585);
DISPLAY 0.617021 (635 2585);
PAINT ORANGE (635 2585);
FORCEPROP 2 LASTPIN (625 2675) $PN 13
J 0
(635 2685);
DISPLAY 0.617021 (635 2685);
PAINT ORANGE (635 2685);
FORCEPROP 2 LASTPIN (625 2725) $PN 14
J 0
(635 2735);
DISPLAY 0.617021 (635 2735);
PAINT ORANGE (635 2735);
FORCEPROP 2 LASTPIN (625 2775) $PN 18
J 0
(635 2785);
DISPLAY 0.617021 (635 2785);
PAINT ORANGE (635 2785);
FORCEPROP 2 LASTPIN (625 2975) $PN 5
J 0
(635 2985);
DISPLAY 0.617021 (635 2985);
PAINT ORANGE (635 2985);
FORCEPROP 2 LASTPIN (625 3025) $PN 3
J 0
(635 3035);
DISPLAY 0.617021 (635 3035);
PAINT ORANGE (635 3035);
FORCEPROP 2 LASTPIN (625 2825) $PN 31
J 0
(635 2835);
DISPLAY 0.617021 (635 2835);
PAINT ORANGE (635 2835);
FORCEPROP 2 LASTPIN (625 2875) $PN 32
J 0
(635 2885);
DISPLAY 0.617021 (635 2885);
PAINT ORANGE (635 2885);
FORCEPROP 2 LASTPIN (625 3125) $PN 17
J 0
(635 3135);
DISPLAY 0.617021 (635 3135);
PAINT ORANGE (635 3135);
FORCEPROP 2 LASTPIN (625 3225) $PN 11
J 0
(635 3235);
DISPLAY 0.617021 (635 3235);
PAINT ORANGE (635 3235);
FORCEPROP 2 LASTPIN (625 3425) $PN 12
J 0
(635 3435);
DISPLAY 0.617021 (635 3435);
PAINT ORANGE (635 3435);
FORCEPROP 2 LASTPIN (625 3575) $PN 9
J 0
(635 3585);
DISPLAY 0.617021 (635 3585);
PAINT ORANGE (635 3585);
FORCEPROP 2 LAST CDS_LOCATION EU4D5
J 0
(-225 3750);
PAINT WHITE (-225 3750);
DISPLAY INVISIBLE (-225 3750);
FORCEPROP 2 LAST SEC 1
J 0
(-225 3800);
DISPLAY 0.680851 (-225 3800);
PAINT MONO (-225 3800);
DISPLAY INVISIBLE (-225 3800);
FORCEPROP 2 LAST SEC_TYPE QFN
J 0
(-225 3800);
DISPLAY 1.021277 (-225 3800);
PAINT ORANGE (-225 3800);
DISPLAY INVISIBLE (-225 3800);
FORCEPROP 1 LAST PACK_TYPE QFN
J 0
(-225 3800);
PAINT SKYBLUE (-225 3800);
DISPLAY INVISIBLE (-225 3800);
FORCEPROP 1 LAST CDS_LMAN_SYM_OUTLINE -400,850,400,-850
J 0
(175 2825);
DISPLAY 0.468085 (175 2825);
PAINT GREEN (175 2825);
DISPLAY INVISIBLE (175 2825);
FORCEPROP 2 LAST CDS_LIB mstr_controller
J 0
(175 2825);
PAINT ORANGE (175 2825);
DISPLAY INVISIBLE (175 2825);
FORCEPROP 1 LAST PATH I96
J 0
(275 3701);
PAINT WHITE (275 3701);
DISPLAY INVISIBLE (275 3701);
FORCEADD DNS..2
(1605 4070);
PAINT RED (1605 4070);
FORCEPROP 1 LAST COMMENT_BODY TRUE
R 1
J 0
(1680 3845);
DISPLAY 0.872340 (1680 3845);
PAINT GREEN (1680 3845);
DISPLAY INVISIBLE (1680 3845);
FORCEPROP 2 LAST CDS_LIB mstr_misc
J 0
(1605 4070);
PAINT ORANGE (1605 4070);
DISPLAY INVISIBLE (1605 4070);
FORCEADD INTEL_CORP_BPAGE..1
(4250 200);
FORCEPROP 1 LAST CDS_CON_LAST_MODIFIED Tue Dec 01 11:52:24 2015
J 0
(2825 525);
PAINT ORANGE (2825 525);
DISPLAY INVISIBLE (2825 525);
FORCEPROP 1 LAST CUSTOM_TXT_CDS <CURRENT_DESIGN_SHEET> OF <TOTAL_DESIGN_SHEETS>
J 0
(3750 225);
PAINT GREEN (3750 225);
FORCEPROP 1 LAST CUSTOM_TXT_CDS <CON_LAST_MODIFIED>
J 0
(2325 550);
PAINT GREEN (2325 550);
FORCEPROP 2 LAST CUSTOM_TXT_CDS <XR_PAGE_TITLE>
J 0
(-3640 5450);
DISPLAY 0.638298 (-3640 5450);
PAINT PINK (-3640 5450);
DISPLAY INVISIBLE (-3640 5450);
FORCEPROP 1 LAST SCH_TITLE PVCCIO CPU1 (1 OF 2)
J 0
(-3700 250);
DISPLAY 1.212766 (-3700 250);
PAINT ORANGE (-3700 250);
FORCEPROP 1 LAST SCH_ADDRESS2 P.O. BOX 58119
J 0
(275 275);
DISPLAY 0.617021 (275 275);
PAINT GREEN (275 275);
FORCEPROP 1 LAST SCH_ADDRESS1 2200 Mission College Blvd.
J 0
(275 325);
DISPLAY 0.617021 (275 325);
PAINT GREEN (275 325);
FORCEPROP 1 LAST SCH_ADDRESS3 Santa Clara, CA 95052-8119
J 0
(275 225);
DISPLAY 0.617021 (275 225);
PAINT GREEN (275 225);
FORCEPROP 1 LAST SCH_NUMBER H4694802
J 0
(2950 350);
DISPLAY 1.212766 (2950 350);
PAINT YELLOW (2950 350);
FORCEPROP 1 LAST SCH_DEPT BESD
J 1
(-200 300);
DISPLAY 1.212766 (-200 300);
PAINT YELLOW (-200 300);
FORCEPROP 1 LAST SCH_REV 2.420
J 0
(4000 350);
DISPLAY 0.978723 (4000 350);
PAINT YELLOW (4000 350);
FORCEPROP 2 LAST PAGE_BORDER TRUE
J 0
(-3640 5450);
DISPLAY 0.638298 (-3640 5450);
PAINT PINK (-3640 5450);
DISPLAY INVISIBLE (-3640 5450);
FORCEPROP 1 LAST COMMENT_BODY TRUE
J 0
(4262 212);
DISPLAY 0.468085 (4262 212);
PAINT GREEN (4262 212);
DISPLAY INVISIBLE (4262 212);
FORCEPROP 2 LAST CDS_LIB mstr_symbols
J 0
(4250 200);
PAINT MONO (4250 200);
DISPLAY INVISIBLE (4250 200);
FORCEPROP 2 LAST CDS_XR_PAGE_TITLE CR-213 : @BASEBOARD_FAB2_LIB.BASEBOARD_FAB2(SCH_1):PAGE213
J 0
(-3640 5450);
DISPLAY 0.638298 (-3640 5450);
PAINT PINK (-3640 5450);
DISPLAY INVISIBLE (-3640 5450);
FORCEADD DNS..2
(-1370 4470);
PAINT RED (-1370 4470);
FORCEPROP 1 LAST COMMENT_BODY TRUE
R 1
J 0
(-1295 4245);
DISPLAY 0.872340 (-1295 4245);
PAINT GREEN (-1295 4245);
DISPLAY INVISIBLE (-1295 4245);
FORCEPROP 2 LAST CDS_LIB mstr_misc
J 0
(-1370 4470);
PAINT ORANGE (-1370 4470);
DISPLAY INVISIBLE (-1370 4470);
FORCEADD DESIGN_NOTE..1
(-225 1675);
FORCEPROP 0 LAST L1 SMBUS ADDRESS:0XB4
J 0
(-425 1550);
DISPLAY 1.021277 (-425 1550);
PAINT ORANGE (-425 1550);
FORCEPROP 2 LAST CDS_LIB mstr_symbols
J 0
(-225 1675);
PAINT ORANGE (-225 1675);
DISPLAY INVISIBLE (-225 1675);
FORCEPROP 1 LAST COMMENT_BODY TRUE
J 0
(-200 1775);
DISPLAY 0.978723 (-200 1775);
PAINT ORANGE (-200 1775);
DISPLAY INVISIBLE (-200 1775);
FORCEADD DNS..2
(-1020 4270);
PAINT RED (-1020 4270);
FORCEPROP 1 LAST COMMENT_BODY TRUE
R 1
J 0
(-945 4045);
DISPLAY 0.872340 (-945 4045);
PAINT GREEN (-945 4045);
DISPLAY INVISIBLE (-945 4045);
FORCEPROP 2 LAST CDS_LIB mstr_misc
J 0
(-1020 4270);
PAINT ORANGE (-1020 4270);
DISPLAY INVISIBLE (-1020 4270);
FORCEADD DESIGN_NOTE..1
(2900 4975);
FORCEPROP 0 LAST L1 SVID ADDRESS:0X2
J 0
(2700 4850);
DISPLAY 1.021277 (2700 4850);
PAINT ORANGE (2700 4850);
FORCEPROP 1 LAST COMMENT_BODY TRUE
J 0
(2925 5075);
DISPLAY 0.978723 (2925 5075);
PAINT ORANGE (2925 5075);
DISPLAY INVISIBLE (2925 5075);
FORCEPROP 2 LAST CDS_LIB mstr_symbols
J 0
(2900 4975);
PAINT ORANGE (2900 4975);
DISPLAY INVISIBLE (2900 4975);
FORCEADD DNS..2
(-2045 4420);
PAINT RED (-2045 4420);
FORCEPROP 1 LAST COMMENT_BODY TRUE
R 1
J 0
(-1970 4195);
DISPLAY 0.872340 (-1970 4195);
PAINT GREEN (-1970 4195);
DISPLAY INVISIBLE (-1970 4195);
FORCEPROP 2 LAST CDS_LIB mstr_misc
J 0
(-2045 4420);
PAINT ORANGE (-2045 4420);
DISPLAY INVISIBLE (-2045 4420);
WIRE 16 -1 (950 4150)(950 4500);
WIRE 16 -1 (950 4500)(1600 4500);
WIRE 16 -1 (1600 4175)(1600 4500);
WIRE 16 -1 (1875 4500)(1600 4500);
WIRE 16 -1 (2175 4500)(1875 4500);
WIRE 16 -1 (1875 4500)(1875 4675);
WIRE 16 -1 (2175 4150)(2175 4500);
WIRE 16 -1 (2425 1325)(2425 1475);
WIRE 16 -1 (2025 1425)(2025 1475);
WIRE 16 -1 (150 4000)(150 4050);
WIRE 16 -1 (625 2275)(1000 2275);
WIRE 16 -1 (1000 2275)(1000 2125);
WIRE 16 -1 (1000 2075)(1000 2125);
WIRE 16 -1 (1000 2125)(625 2125);
WIRE 16 -1 (625 2075)(1000 2075);
WIRE 16 -1 (1000 1925)(1000 2075);
WIRE 16 -1 (-1025 4375)(-1025 4675);
WIRE 16 -1 (-1025 4675)(-550 4675);
WIRE 16 -1 (-550 4600)(-550 4675);
WIRE 16 -1 (-550 4675)(-550 4775);
WIRE 16 -1 (-1375 4575)(-1375 4850);
WIRE 16 -1 (-2050 4525)(-2050 4825);
WIRE 16 -1 (-250 4000)(-250 4050);
WIRE 16 -1 (-525 1225)(-525 1000);
WIRE 16 -1 (-525 1000)(-850 1000);
WIRE 16 -1 (-850 1225)(-850 1000);
WIRE 16 -1 (-850 1000)(-850 800);
WIRE 16 -1 (-275 2125)(-950 2125);
WIRE 16 -1 (-950 2075)(-950 2125);
WIRE 16 -1 (-2425 4050)(-2425 4150);
WIRE 16 -1 (-2650 4050)(-2650 4150);
WIRE 16 -1 (1750 2600)(1750 2550);
WIRE 16 -1 (-2425 4800)(-2425 4925);
WIRE 16 -1 (-2425 4425)(-2425 4600);
WIRE 16 -1 (-2425 4350)(-2425 4425);
WIRE 16 -1 (-2425 4425)(-2650 4425);
WIRE 16 -1 (-2650 4350)(-2650 4425);
WIRE 16 -1 (-2650 4425)(-3200 4425);
FORCEPROP 2 LAST SIG_NAME VR_PVCCIO_CPU1_VINSEN
J 0
(-3215 4440);
DISPLAY 0.617021 (-3215 4440);
PAINT ORANGE (-3215 4440);
WIRE 16 -1 (-2625 2925)(-1375 2925);
FORCEPROP 2 LAST SIG_NAME SVID_DIO0_CPU1_R
J 0
(-2650 2935);
DISPLAY 0.617021 (-2650 2935);
PAINT ORANGE (-2650 2935);
WIRE 16 -1 (-1375 4375)(-1375 2925);
WIRE 16 -1 (-1375 2925)(-1275 2925);
WIRE 16 -1 (150 4250)(150 4300);
WIRE 16 -1 (150 4300)(-250 4300);
WIRE 16 -1 (-250 4250)(-250 4300);
WIRE 16 -1 (-250 4300)(-550 4300);
WIRE 16 -1 (-550 4400)(-550 4300);
WIRE 16 -1 (-550 4300)(-550 3575);
FORCEPROP 2 LAST SIG_NAME VR_PVCCIO_CPU1_VDD
R 1
J 0
(-550 3715);
DISPLAY 0.617021 (-550 3715);
PAINT ORANGE (-550 3715);
FORCEPROP 2 LASTPROP $XRERR UNIQUE?
J 0
(-790 3715);
DISPLAY 0.638298 (-790 3715);
PAINT MONO (-790 3715);
DISPLAY INVISIBLE (-790 3715);
WIRE 16 -1 (-550 3575)(-275 3575);
FORCEPROP 0 LAST VOLTAGE 3.3
J 0
(-400 3625);
DISPLAY 1.021277 (-400 3625);
PAINT SKYBLUE (-400 3625);
DISPLAY INVISIBLE (-400 3625);
WIRE 16 -1 (2050 3575)(2675 3575);
FORCEPROP 2 LAST SIG_NAME PWRGD_PVCCIO_CPU1
J 0
(2219 3577);
DISPLAY 0.617021 (2219 3577);
PAINT ORANGE (2219 3577);
WIRE 16 -1 (2175 3950)(2175 3225);
WIRE 16 -1 (625 3225)(2175 3225);
FORCEPROP 2 LAST SIG_NAME IRQ_PVCCIO_CPU1_VRHOT_N
J 0
(750 3240);
DISPLAY 0.617021 (750 3240);
PAINT ORANGE (750 3240);
FORCEPROP 2 LASTPROP $XRERR UNIQUE?
J 0
(510 3240);
DISPLAY 0.638298 (510 3240);
PAINT MONO (510 3240);
DISPLAY INVISIBLE (510 3240);
WIRE 16 -1 (2425 1675)(2425 1750);
WIRE 16 -1 (2425 1750)(2750 1750);
WIRE 16 -1 (2425 1750)(2025 1750);
FORCEPROP 2 LAST SIG_NAME VR_PVCCIO_CPU1_VD12
J 0
(2110 1765);
DISPLAY 0.617021 (2110 1765);
PAINT ORANGE (2110 1765);
WIRE 16 -1 (2025 1675)(2025 1750);
WIRE 16 -1 (1475 3125)(2725 3125);
FORCEPROP 2 LAST SIG_NAME SVID_ALERT0_CPU1_R_N
J 0
(2150 3135);
DISPLAY 0.617021 (2150 3135);
PAINT ORANGE (2150 3135);
WIRE 16 -1 (2725 2975)(625 2975);
FORCEPROP 0 LAST VOLTAGE 3.6
J 0
(2150 3050);
DISPLAY 1.021277 (2150 3050);
PAINT SKYBLUE (2150 3050);
DISPLAY INVISIBLE (2150 3050);
FORCEPROP 2 LAST SIG_NAME VR_PVCCIO_CPU1_PWM1
J 0
(2150 2990);
DISPLAY 0.617021 (2150 2990);
PAINT ORANGE (2150 2990);
WIRE 16 -1 (1750 2800)(1750 3575);
WIRE 16 -1 (1750 3575)(1850 3575);
WIRE 16 -1 (1750 3575)(950 3575);
FORCEPROP 2 LAST SIG_NAME PWRGD_PVCCIO_CPU1_R
J 0
(1035 3590);
DISPLAY 0.617021 (1035 3590);
PAINT ORANGE (1035 3590);
FORCEPROP 2 LASTPROP $XRERR UNIQUE?
J 0
(795 3590);
DISPLAY 0.638298 (795 3590);
PAINT MONO (795 3590);
DISPLAY INVISIBLE (795 3590);
WIRE 16 -1 (950 3950)(950 3575);
WIRE 16 -1 (625 3575)(950 3575);
WIRE 16 -1 (1600 3975)(1600 2875);
WIRE 16 -1 (625 2875)(1600 2875);
FORCEPROP 2 LAST SIG_NAME PU_VR_PVCCIO_CPU1_FAULT1
J 0
(725 2890);
DISPLAY 0.617021 (725 2890);
PAINT ORANGE (725 2890);
FORCEPROP 2 LASTPROP $XRERR UNIQUE?
J 0
(485 2890);
DISPLAY 0.638298 (485 2890);
PAINT MONO (485 2890);
DISPLAY INVISIBLE (485 2890);
WIRE 16 -1 (625 2675)(1350 2675);
FORCEPROP 2 LAST SIG_NAME TP_VR_PVCCIO_CPU1_MP0
J 0
(750 2690);
DISPLAY 0.617021 (750 2690);
PAINT ORANGE (750 2690);
FORCEPROP 2 LASTPROP $XRERR UNIQUE?
J 0
(1380 2675);
DISPLAY 0.638298 (1380 2675);
PAINT MONO (1380 2675);
DISPLAY INVISIBLE (1380 2675);
WIRE 16 -1 (625 2825)(1350 2825);
FORCEPROP 2 LAST SIG_NAME TP_VR_PVCCIO_CPU1_MP3
J 0
(750 2840);
DISPLAY 0.617021 (750 2840);
PAINT ORANGE (750 2840);
FORCEPROP 2 LASTPROP $XRERR UNIQUE?
J 0
(1380 2825);
DISPLAY 0.638298 (1380 2825);
PAINT MONO (1380 2825);
DISPLAY INVISIBLE (1380 2825);
WIRE 16 -1 (625 2775)(1350 2775);
FORCEPROP 2 LAST SIG_NAME TP_VR_PVCCIO_CPU1_MP2
J 0
(750 2790);
DISPLAY 0.617021 (750 2790);
PAINT ORANGE (750 2790);
FORCEPROP 2 LASTPROP $XRERR UNIQUE?
J 0
(1380 2775);
DISPLAY 0.638298 (1380 2775);
PAINT MONO (1380 2775);
DISPLAY INVISIBLE (1380 2775);
WIRE 16 -1 (625 2725)(1350 2725);
FORCEPROP 2 LAST SIG_NAME TP_VR_PVCCIO_CPU1_MP1
J 0
(750 2740);
DISPLAY 0.617021 (750 2740);
PAINT ORANGE (750 2740);
FORCEPROP 2 LASTPROP $XRERR UNIQUE?
J 0
(1380 2725);
DISPLAY 0.638298 (1380 2725);
PAINT MONO (1380 2725);
DISPLAY INVISIBLE (1380 2725);
WIRE 16 -1 (625 2375)(1275 2375);
FORCEPROP 2 LAST SIG_NAME NC_PVCCIO_CPU1_DNC0
J 0
(725 2390);
DISPLAY 0.617021 (725 2390);
PAINT ORANGE (725 2390);
FORCEPROP 2 LASTPROP $XRERR UNIQUE?
J 0
(1305 2375);
DISPLAY 0.638298 (1305 2375);
PAINT MONO (1305 2375);
DISPLAY INVISIBLE (1305 2375);
WIRE 16 -1 (625 2425)(1275 2425);
FORCEPROP 2 LAST SIG_NAME NC_PVCCIO_CPU1_DNC1
J 0
(725 2440);
DISPLAY 0.617021 (725 2440);
PAINT ORANGE (725 2440);
FORCEPROP 2 LASTPROP $XRERR UNIQUE?
J 0
(1305 2425);
DISPLAY 0.638298 (1305 2425);
PAINT MONO (1305 2425);
DISPLAY INVISIBLE (1305 2425);
WIRE 16 -1 (625 2475)(1275 2475);
FORCEPROP 2 LAST SIG_NAME NC_PVCCIO_CPU1_DNC2
J 0
(725 2490);
DISPLAY 0.617021 (725 2490);
PAINT ORANGE (725 2490);
FORCEPROP 2 LASTPROP $XRERR UNIQUE?
J 0
(1305 2475);
DISPLAY 0.638298 (1305 2475);
PAINT MONO (1305 2475);
DISPLAY INVISIBLE (1305 2475);
WIRE 16 -1 (625 2525)(1275 2525);
FORCEPROP 2 LAST SIG_NAME NC_PVCCIO_CPU1_DNC3
J 0
(725 2540);
DISPLAY 0.617021 (725 2540);
PAINT ORANGE (725 2540);
FORCEPROP 2 LASTPROP $XRERR UNIQUE?
J 0
(1305 2525);
DISPLAY 0.638298 (1305 2525);
PAINT MONO (1305 2525);
DISPLAY INVISIBLE (1305 2525);
WIRE 16 -1 (625 2575)(1275 2575);
FORCEPROP 2 LAST SIG_NAME NC_PVCCIO_CPU1_DNC4
J 0
(725 2590);
DISPLAY 0.617021 (725 2590);
PAINT ORANGE (725 2590);
FORCEPROP 2 LASTPROP $XRERR UNIQUE?
J 0
(1305 2575);
DISPLAY 0.638298 (1305 2575);
PAINT MONO (1305 2575);
DISPLAY INVISIBLE (1305 2575);
WIRE 16 -1 (625 3025)(1150 3025);
FORCEPROP 2 LAST SIG_NAME TP_PVCCIO_CPU1_BPWM1
J 0
(725 3040);
DISPLAY 0.617021 (725 3040);
PAINT ORANGE (725 3040);
FORCEPROP 2 LASTPROP $XRERR UNIQUE?
J 0
(1180 3025);
DISPLAY 0.638298 (1180 3025);
PAINT MONO (1180 3025);
DISPLAY INVISIBLE (1180 3025);
WIRE 16 -1 (625 3425)(1325 3425);
FORCEPROP 2 LAST SIG_NAME TP_PVCCIO_CPU1_PINALRT_N
J 0
(725 3440);
DISPLAY 0.617021 (725 3440);
PAINT ORANGE (725 3440);
FORCEPROP 2 LASTPROP $XRERR UNIQUE?
J 0
(1355 3425);
DISPLAY 0.638298 (1355 3425);
PAINT MONO (1355 3425);
DISPLAY INVISIBLE (1355 3425);
WIRE 16 -1 (1275 3125)(625 3125);
FORCEPROP 2 LAST SIG_NAME SVID_ALERT_PVCCIO_CPU1
J 0
(725 3140);
DISPLAY 0.617021 (725 3140);
PAINT ORANGE (725 3140);
FORCEPROP 2 LASTPROP $XRERR UNIQUE?
J 0
(485 3140);
DISPLAY 0.638298 (485 3140);
PAINT MONO (485 3140);
DISPLAY INVISIBLE (485 3140);
WIRE 16 -1 (-275 3225)(-1025 3225);
FORCEPROP 0 LAST VOLTAGE 3.3
J 0
(-650 3275);
DISPLAY 1.021277 (-650 3275);
PAINT SKYBLUE (-650 3275);
DISPLAY INVISIBLE (-650 3275);
WIRE 16 -1 (-1025 4175)(-1025 3225);
WIRE 16 -1 (-1825 3225)(-1025 3225);
FORCEPROP 2 LAST SIG_NAME VR_PVCCIO_CPU1_EN
J 0
(-1825 3240);
DISPLAY 0.617021 (-1825 3240);
PAINT ORANGE (-1825 3240);
FORCEPROP 2 LASTPROP $XRERR UNIQUE?
J 0
(-2065 3240);
DISPLAY 0.638298 (-2065 3240);
PAINT MONO (-2065 3240);
DISPLAY INVISIBLE (-2065 3240);
WIRE 16 -1 (-1925 3925)(-2050 3925);
WIRE 16 -1 (-2050 4325)(-2050 3925);
WIRE 16 -1 (-2825 3925)(-2050 3925);
FORCEPROP 0 LAST SIG_NAME SVID_CLK0_CPU1_R
J 0
(-2875 3935);
DISPLAY 0.617021 (-2875 3935);
PAINT ORANGE (-2875 3935);
WIRE 16 -1 (-275 3525)(-850 3525);
WIRE 16 -1 (-850 3525)(-850 3925);
WIRE 16 -1 (-1725 3925)(-850 3925);
FORCEPROP 2 LAST SIG_NAME SVID_CLK_PVCCIO_CPU1
J 0
(-1590 3940);
DISPLAY 0.617021 (-1590 3940);
PAINT ORANGE (-1590 3940);
FORCEPROP 2 LASTPROP $XRERR UNIQUE?
J 0
(-1830 3940);
DISPLAY 0.638298 (-1830 3940);
PAINT MONO (-1830 3940);
DISPLAY INVISIBLE (-1830 3940);
WIRE 16 -1 (-800 2775)(-275 2775);
FORCEPROP 2 LAST SIG_NAME TP_PVCCIO_CPU1_RESET_N
J 0
(-800 2790);
DISPLAY 0.617021 (-800 2790);
PAINT ORANGE (-800 2790);
FORCEPROP 2 LASTPROP $XRERR UNIQUE?
J 0
(-1040 2775);
DISPLAY 0.638298 (-1040 2775);
PAINT MONO (-1040 2775);
DISPLAY INVISIBLE (-1040 2775);
WIRE 16 -1 (-275 2075)(-850 2075);
FORCEPROP 0 LAST VOLTAGE 3.3
J 0
(-550 2125);
DISPLAY 1.021277 (-550 2125);
PAINT SKYBLUE (-550 2125);
DISPLAY INVISIBLE (-550 2125);
WIRE 16 -1 (-850 1425)(-850 2075);
FORCEPROP 0 LAST SIG_NAME VR_PVCCIO_CPU1_XADDR1
R 1
J 0
(-860 1460);
DISPLAY 0.617021 (-860 1460);
PAINT ORANGE (-860 1460);
FORCEPROP 2 LASTPROP $XRERR UNIQUE?
J 0
(-1100 1460);
DISPLAY 0.638298 (-1100 1460);
PAINT MONO (-1100 1460);
DISPLAY INVISIBLE (-1100 1460);
WIRE 16 -1 (-950 2275)(-275 2275);
FORCEPROP 2 LAST SIG_NAME TP_PVCCIO_CPU1_BTSEN
J 0
(-925 2290);
DISPLAY 0.617021 (-925 2290);
PAINT ORANGE (-925 2290);
FORCEPROP 2 LASTPROP $XRERR UNIQUE?
J 0
(-1190 2275);
DISPLAY 0.638298 (-1190 2275);
PAINT MONO (-1190 2275);
DISPLAY INVISIBLE (-1190 2275);
WIRE 16 -1 (-950 2175)(-275 2175);
FORCEPROP 2 LAST SIG_NAME TP_PVCCIO_CPU1_BIREF1
J 0
(-925 2190);
DISPLAY 0.617021 (-925 2190);
PAINT ORANGE (-925 2190);
FORCEPROP 2 LASTPROP $XRERR UNIQUE?
J 0
(-1190 2175);
DISPLAY 0.638298 (-1190 2175);
PAINT MONO (-1190 2175);
DISPLAY INVISIBLE (-1190 2175);
WIRE 16 -1 (-975 2575)(-275 2575);
FORCEPROP 2 LAST SIG_NAME TP_PVCCIO_CPU1_BVSEN
J 0
(-875 2590);
DISPLAY 0.617021 (-875 2590);
PAINT ORANGE (-875 2590);
FORCEPROP 2 LASTPROP $XRERR UNIQUE?
J 0
(-1215 2575);
DISPLAY 0.638298 (-1215 2575);
PAINT MONO (-1215 2575);
DISPLAY INVISIBLE (-1215 2575);
WIRE 16 -1 (-975 2525)(-275 2525);
FORCEPROP 2 LAST SIG_NAME TP_PVCCIO_CPU1_BVREF
J 0
(-875 2540);
DISPLAY 0.617021 (-875 2540);
PAINT ORANGE (-875 2540);
FORCEPROP 2 LASTPROP $XRERR UNIQUE?
J 0
(-1215 2525);
DISPLAY 0.638298 (-1215 2525);
PAINT MONO (-1215 2525);
DISPLAY INVISIBLE (-1215 2525);
WIRE 16 -1 (-275 2625)(-1725 2625);
WIRE 16 -1 (-1725 1525)(-1725 2625);
WIRE 16 -1 (-1725 1525)(-2075 1525);
WIRE 16 -1 (-2075 1625)(-2075 1525);
WIRE 16 -1 (-3125 1525)(-2075 1525);
FORCEPROP 2 LAST SIG_NAME VSENSE_PVCCIO_CPU1_AVSN
J 0
(-3140 1540);
DISPLAY 0.617021 (-3140 1540);
PAINT ORANGE (-3140 1540);
WIRE 16 -1 (-275 2675)(-1900 2675);
WIRE 16 -1 (-1900 2675)(-1900 1925);
WIRE 16 -1 (-2075 1925)(-1900 1925);
WIRE 16 -1 (-2075 1825)(-2075 1925);
WIRE 16 -1 (-2225 1925)(-2075 1925);
FORCEPROP 0 LAST VOLTAGE 1.05
J 0
(-2075 2000);
DISPLAY 1.021277 (-2075 2000);
PAINT SKYBLUE (-2075 2000);
DISPLAY INVISIBLE (-2075 2000);
FORCEPROP 2 LAST SIG_NAME VR_PVCCIO_CPU1_AVSP
J 0
(-1865 2690);
DISPLAY 0.617021 (-1865 2690);
PAINT ORANGE (-1865 2690);
FORCEPROP 2 LASTPROP $XRERR UNIQUE?
J 0
(-2105 2690);
DISPLAY 0.638298 (-2105 2690);
PAINT MONO (-2105 2690);
DISPLAY INVISIBLE (-2105 2690);
WIRE 16 -1 (-1075 2425)(-275 2425);
FORCEPROP 2 LAST SIG_NAME SMB_VR_SDA_PVCCIO_CPU1
J 0
(-975 2440);
DISPLAY 0.617021 (-975 2440);
PAINT ORANGE (-975 2440);
FORCEPROP 2 LASTPROP $XRERR UNIQUE?
J 0
(-1215 2440);
DISPLAY 0.638298 (-1215 2440);
PAINT MONO (-1215 2440);
DISPLAY INVISIBLE (-1215 2440);
WIRE 16 -1 (-1400 2375)(-275 2375);
FORCEPROP 2 LAST SIG_NAME SMB_VR_SCL_PVCCIO_CPU1
J 0
(-975 2390);
DISPLAY 0.617021 (-975 2390);
PAINT ORANGE (-975 2390);
FORCEPROP 2 LASTPROP $XRERR UNIQUE?
J 0
(-1215 2390);
DISPLAY 0.638298 (-1215 2390);
PAINT MONO (-1215 2390);
DISPLAY INVISIBLE (-1215 2390);
WIRE 16 -1 (-1075 2925)(-275 2925);
FORCEPROP 2 LAST SIG_NAME SVID_VDIO_PVCCIO_CPU1
J 0
(-975 2940);
DISPLAY 0.617021 (-975 2940);
PAINT ORANGE (-975 2940);
FORCEPROP 2 LASTPROP $XRERR UNIQUE?
J 0
(-1215 2940);
DISPLAY 0.638298 (-1215 2940);
PAINT MONO (-1215 2940);
DISPLAY INVISIBLE (-1215 2940);
WIRE 16 -1 (-275 3075)(-1225 3075);
FORCEPROP 2 LAST SIG_NAME TP_VR_PVCCIO_CPU1_AIINSEN
J 0
(-1175 3085);
DISPLAY 0.617021 (-1175 3085);
PAINT ORANGE (-1175 3085);
FORCEPROP 2 LASTPROP $XRERR UNIQUE?
J 0
(-1465 3075);
DISPLAY 0.638298 (-1465 3075);
PAINT MONO (-1465 3075);
DISPLAY INVISIBLE (-1465 3075);
WIRE 16 -1 (-525 2025)(-275 2025);
FORCEPROP 0 LAST VOLTAGE 3.3
J 0
(-400 2075);
DISPLAY 1.021277 (-400 2075);
PAINT SKYBLUE (-400 2075);
DISPLAY INVISIBLE (-400 2075);
WIRE 16 -1 (-525 1425)(-525 2025);
FORCEPROP 0 LAST SIG_NAME VR_PVCCIO_CPU1_XADDR2
R 1
J 0
(-535 1435);
DISPLAY 0.617021 (-535 1435);
PAINT ORANGE (-535 1435);
FORCEPROP 2 LASTPROP $XRERR UNIQUE?
J 0
(-775 1435);
DISPLAY 0.638298 (-775 1435);
PAINT MONO (-775 1435);
DISPLAY INVISIBLE (-775 1435);
WIRE 16 -1 (-275 3425)(-2075 3425);
WIRE 16 -1 (-2075 3675)(-2075 3425);
WIRE 16 -1 (-2075 3425)(-2625 3425);
FORCEPROP 2 LAST SIG_NAME VR_PVCCIO_CPU1_AIREF1
J 0
(-2650 3440);
DISPLAY 0.617021 (-2650 3440);
PAINT ORANGE (-2650 3440);
WIRE 16 -1 (-2325 3675)(-2075 3675);
WIRE 16 -1 (-2625 3375)(-275 3375);
FORCEPROP 2 LAST SIG_NAME ISENSE_PVCCIO_CPU1_PH1_IMON
J 2
(-2017 3395);
DISPLAY 0.617021 (-2017 3395);
PAINT ORANGE (-2017 3395);
WIRE 16 -1 (-275 3125)(-2625 3125);
FORCEPROP 2 LAST SIG_NAME VR_PVCCIO_CPU1_VINSEN
J 0
(-2650 3140);
DISPLAY 0.617021 (-2650 3140);
PAINT ORANGE (-2650 3140);
WIRE 16 -1 (-2625 3225)(-2025 3225);
FORCEPROP 2 LAST SIG_NAME FM_PVCCIO_CPU1_EN
J 0
(-2625 3240);
DISPLAY 0.617021 (-2625 3240);
PAINT ORANGE (-2625 3240);
WIRE 16 -1 (-2625 3275)(-275 3275);
FORCEPROP 2 LAST SIG_NAME A_TSENSE_PVCCIO_CPU1
J 2
(-2127 3294);
DISPLAY 0.617021 (-2127 3294);
PAINT ORANGE (-2127 3294);
WIRE 16 -1 (-275 2975)(-2625 2975);
FORCEPROP 2 LAST SIG_NAME VR_PVCCIO_CPU1_VD12
J 0
(-2650 2990);
DISPLAY 0.617021 (-2650 2990);
PAINT ORANGE (-2650 2990);
WIRE 16 -1 (-2625 2375)(-1600 2375);
FORCEPROP 2 LAST SIG_NAME SMB_VR_STBY_LVC3_SCL
J 0
(-2650 2390);
DISPLAY 0.617021 (-2650 2390);
PAINT ORANGE (-2650 2390);
WIRE 16 -1 (-2625 2425)(-1275 2425);
FORCEPROP 2 LAST SIG_NAME SMB_VR_STBY_LVC3_SDA
J 0
(-2650 2440);
DISPLAY 0.617021 (-2650 2440);
PAINT ORANGE (-2650 2440);
WIRE 16 -1 (-2525 3675)(-3125 3675);
FORCEPROP 2 LAST SIG_NAME VR_PVCCIO_CPU1_VD12
J 0
(-3150 3690);
DISPLAY 0.617021 (-3150 3690);
PAINT ORANGE (-3150 3690);
WIRE 16 -1 (-2425 1925)(-3125 1925);
FORCEPROP 2 LAST SIG_NAME VSENSE_PVCCIO_CPU1_AVSP
J 0
(-3140 1940);
DISPLAY 0.617021 (-3140 1940);
PAINT ORANGE (-3140 1940);
DOT 1 (-2075 1525);
DOT 1 (-2075 1925);
DOT 1 (-2075 3425);
DOT 1 (-2050 3925);
DOT 1 (-850 1000);
DOT 1 (-1375 2925);
DOT 1 (-1025 3225);
DOT 1 (-2650 4425);
DOT 1 (-2425 4425);
DOT 1 (-550 4300);
DOT 1 (-550 4675);
DOT 1 (-250 4300);
DOT 1 (1000 2125);
DOT 1 (1000 2075);
DOT 1 (950 3575);
DOT 1 (1750 3575);
DOT 1 (2425 1750);
DOT 1 (1600 4500);
DOT 1 (1875 4500);
FORCENOTE
ROOM = PVCCIO_CPU1
(-3600 450) 0;
DISPLAY LEFT (-3600 450);
DISPLAY 1.021277 (-3600 450);
PAINT PURPLE (-3600 450);
FORCENOTE
BOM_COST = PROC_VRD_PVCCIO_CPU1
(-3600 375) 0;
DISPLAY LEFT (-3600 375);
DISPLAY 1.021277 (-3600 375);
PAINT PURPLE (-3600 375);
QUIT
